FILE_TYPE = MACRO_DRAWING;
SET COLOR_WIRE YELLOW;
SET COLOR_PROP MONO;
SET COLOR_DOT WHITE;
SET COLOR_ARC YELLOW;
SET COLOR_BODY GREEN;
SET COLOR_NOTE MONO;
SET PROP_DISPLAY VALUE;
SET PAGE_NUMBER P175;
FORCEADD TTL2G14..1
(-3725 4175);
FORCEPROP 2 LASTPIN (-3575 4175) $PN 4
J 0
(-3565 4185);
DISPLAY 0.617021 (-3565 4185);
PAINT ORANGE (-3565 4185);
FORCEPROP 1 LAST VALUE 74LVC2G14
J 0
(-3775 4275);
DISPLAY 0.617021 (-3775 4275);
PAINT SKYBLUE (-3775 4275);
FORCEPROP 1 LAST LOCATION U9A4
J 0
(-3775 4375);
DISPLAY 0.617021 (-3775 4375);
PAINT AQUA (-3775 4375);
FORCEPROP 1 LAST MATERIAL IC
J 0
(-3775 4325);
DISPLAY 0.617021 (-3775 4325);
PAINT SKYBLUE (-3775 4325);
FORCEPROP 2 LASTPIN (-3825 4175) $PN 3
J 2
(-3835 4185);
DISPLAY 0.617021 (-3835 4185);
PAINT ORANGE (-3835 4185);
FORCEPROP 1 LAST POWER_GROUP VCC=P3V3_STBY;GND=GND
J 1
(-3375 3985);
DISPLAY 0.617021 (-3375 3985);
PAINT ORANGE (-3375 3985);
FORCEPROP 1 LAST PART_NUMBER D18476-001
J 0
(-3775 4040);
DISPLAY 0.617021 (-3775 4040);
PAINT BLUE (-3775 4040);
FORCEPROP 1 LAST PACK_TYPE SMLF
J 0
(-3775 4425);
DISPLAY 0.978723 (-3775 4425);
PAINT SKYBLUE (-3775 4425);
DISPLAY INVISIBLE (-3775 4425);
FORCEPROP 2 LAST SEC_TYPE SMLF
J 0
(-3775 4425);
DISPLAY 1.021277 (-3775 4425);
PAINT ORANGE (-3775 4425);
DISPLAY INVISIBLE (-3775 4425);
FORCEPROP 2 LAST BOM_COST MIO_CHASSIS
J 0
(-3775 4475);
DISPLAY 1.021277 (-3775 4475);
PAINT ORANGE (-3775 4475);
DISPLAY INVISIBLE (-3775 4475);
FORCEPROP 2 LAST SEC 2
J 0
(-3775 4425);
DISPLAY 0.680851 (-3775 4425);
PAINT MONO (-3775 4425);
DISPLAY INVISIBLE (-3775 4425);
FORCEPROP 2 LAST CDS_LOCATION U9A4
J 0
(-3775 4375);
DISPLAY 0.617021 (-3775 4375);
PAINT AQUA (-3775 4375);
DISPLAY INVISIBLE (-3775 4375);
FORCEPROP 2 LAST ROOM MIO_CHASSIS
J 0
(-3775 4425);
DISPLAY 1.021277 (-3775 4425);
PAINT ORANGE (-3775 4425);
DISPLAY INVISIBLE (-3775 4425);
FORCEPROP 1 LAST PATH I10
J 0
(-3675 4225);
DISPLAY 0.978723 (-3675 4225);
PAINT WHITE (-3675 4225);
DISPLAY INVISIBLE (-3675 4225);
FORCEPROP 2 LAST CDS_LIB mstr_ttl
J 0
(-3725 4175);
PAINT ORANGE (-3725 4175);
DISPLAY INVISIBLE (-3725 4175);
FORCEADD CAP_A..1
(-4975 3950);
FORCEPROP 1 LAST LOCATION C1L18
J 0
(-4925 4050);
DISPLAY 0.617021 (-4925 4050);
PAINT AQUA (-4925 4050);
FORCEPROP 1 LAST PART_NUMBER D97712-004
J 0
(-4925 3800);
DISPLAY 0.617021 (-4925 3800);
PAINT BLUE (-4925 3800);
FORCEPROP 1 LAST VALUE 1.0UF
J 0
(-4925 4000);
DISPLAY 0.617021 (-4925 4000);
PAINT SKYBLUE (-4925 4000);
FORCEPROP 1 LAST TOLERANCE 10%
J 0
(-4925 3900);
DISPLAY 0.617021 (-4925 3900);
PAINT SKYBLUE (-4925 3900);
FORCEPROP 1 LAST PACK_TYPE 0402V
J 0
(-4925 3750);
DISPLAY 0.617021 (-4925 3750);
PAINT SKYBLUE (-4925 3750);
FORCEPROP 1 LAST VOLTAGE 6.3V
J 0
(-4925 3950);
DISPLAY 0.617021 (-4925 3950);
PAINT SKYBLUE (-4925 3950);
FORCEPROP 1 LAST MATERIAL X6S
J 0
(-4925 3850);
DISPLAY 0.617021 (-4925 3850);
PAINT SKYBLUE (-4925 3850);
FORCEPROP 1 LASTPIN (-4975 4050) $PN 1
J 0
(-4965 4030);
DISPLAY 0.617021 (-4965 4030);
PAINT ORANGE (-4965 4030);
FORCEPROP 1 LASTPIN (-4975 3850) $PN 2
J 0
(-4965 3830);
DISPLAY 0.617021 (-4965 3830);
PAINT ORANGE (-4965 3830);
FORCEPROP 2 LAST BOM_COST MIO_CHASSIS
J 0
(-4925 4150);
DISPLAY 1.021277 (-4925 4150);
PAINT ORANGE (-4925 4150);
DISPLAY INVISIBLE (-4925 4150);
FORCEPROP 2 LAST CDS_SEC 1
J 0
(-4925 4100);
PAINT ORANGE (-4925 4100);
DISPLAY INVISIBLE (-4925 4100);
FORCEPROP 2 LAST SEC_TYPE 0402V
J 0
(-4925 4150);
DISPLAY 1.021277 (-4925 4150);
PAINT ORANGE (-4925 4150);
DISPLAY INVISIBLE (-4925 4150);
FORCEPROP 2 LAST SEC 1
J 0
(-4925 4100);
DISPLAY 0.680851 (-4925 4100);
PAINT MONO (-4925 4100);
DISPLAY INVISIBLE (-4925 4100);
FORCEPROP 1 LAST PATH I11
J 0
(-4925 4100);
DISPLAY 0.978723 (-4925 4100);
PAINT WHITE (-4925 4100);
DISPLAY INVISIBLE (-4925 4100);
FORCEPROP 2 LAST ROOM MIO_CHASSIS
J 0
(-4925 4100);
DISPLAY 1.021277 (-4925 4100);
PAINT ORANGE (-4925 4100);
DISPLAY INVISIBLE (-4925 4100);
FORCEPROP 2 LAST CDS_LOCATION C1L18
J 0
(-4925 4050);
DISPLAY 0.617021 (-4925 4050);
PAINT AQUA (-4925 4050);
DISPLAY INVISIBLE (-4925 4050);
FORCEPROP 2 LAST CDS_LIB dev_discrete
J 0
(-4975 3950);
PAINT ORANGE (-4975 3950);
DISPLAY INVISIBLE (-4975 3950);
FORCEADD GND..1
(-4975 3675);
FORCEPROP 3 LASTPIN (-4975 3725) SIG_NAME GND\g
J 0
(-4965 3735);
DISPLAY 0.659574 (-4965 3735);
PAINT MONO (-4965 3735);
DISPLAY INVISIBLE (-4965 3735);
FORCEPROP 1 LAST HDL_POWER GND
J 0
(-4975 3825);
DISPLAY 0.872340 (-4975 3825);
PAINT GREEN (-4975 3825);
DISPLAY INVISIBLE (-4975 3825);
FORCEPROP 1 LAST BODY_TYPE PLUMBING
J 0
(-5020 3632);
DISPLAY 0.340426 (-5020 3632);
PAINT GREEN (-5020 3632);
DISPLAY INVISIBLE (-5020 3632);
FORCEPROP 1 LAST VOLTAGE 0.0V
J 0
(-5020 3632);
DISPLAY 0.340426 (-5020 3632);
PAINT SKYBLUE (-5020 3632);
DISPLAY INVISIBLE (-5020 3632);
FORCEPROP 2 LAST CDS_LIB mstr_symbols
J 0
(-4975 3675);
PAINT ORANGE (-4975 3675);
DISPLAY INVISIBLE (-4975 3675);
FORCEPROP 1 LAST SIZE 1B
J 0
(-4900 3625);
DISPLAY 0.872340 (-4900 3625);
PAINT AQUA (-4900 3625);
DISPLAY INVISIBLE (-4900 3625);
FORCEPROP 1 LAST PATH I12
J 0
(-4900 3675);
DISPLAY 0.872340 (-4900 3675);
PAINT AQUA (-4900 3675);
DISPLAY INVISIBLE (-4900 3675);
FORCEADD RES..1
(-2750 4175);
FORCEPROP 1 LAST PART_NUMBER G21796-074
J 0
(-2800 4275);
DISPLAY 0.617021 (-2800 4275);
PAINT BLUE (-2800 4275);
FORCEPROP 1 LAST LOCATION R1L26
J 0
(-2800 4225);
DISPLAY 0.617021 (-2800 4225);
PAINT AQUA (-2800 4225);
FORCEPROP 1 LASTPIN (-2650 4175) $PN 2
J 0
(-2688 4187);
DISPLAY 0.617021 (-2688 4187);
PAINT ORANGE (-2688 4187);
FORCEPROP 1 LASTPIN (-2850 4175) $PN 1
J 0
(-2838 4187);
DISPLAY 0.617021 (-2838 4187);
PAINT ORANGE (-2838 4187);
FORCEPROP 1 LAST VALUE 33.2
J 2
(-2775 4075);
DISPLAY 0.617021 (-2775 4075);
PAINT SKYBLUE (-2775 4075);
FORCEPROP 1 LAST TOLERANCE 1%
J 0
(-2750 4075);
DISPLAY 0.617021 (-2750 4075);
PAINT SKYBLUE (-2750 4075);
FORCEPROP 1 LAST PACK_TYPE 0402
J 0
(-2500 4025);
DISPLAY 0.617021 (-2500 4025);
PAINT SKYBLUE (-2500 4025);
FORCEPROP 1 LAST MATERIAL CHIP
J 0
(-2750 4025);
DISPLAY 0.617021 (-2750 4025);
PAINT SKYBLUE (-2750 4025);
FORCEPROP 1 LAST WATTAGE 1/16W
J 2
(-2775 4025);
DISPLAY 0.617021 (-2775 4025);
PAINT SKYBLUE (-2775 4025);
FORCEPROP 2 LAST SEC_TYPE 0402
J 0
(-2800 4375);
DISPLAY 1.021277 (-2800 4375);
PAINT ORANGE (-2800 4375);
DISPLAY INVISIBLE (-2800 4375);
FORCEPROP 2 LAST BOM_COST MIO_CHASSIS
J 0
(-2800 4375);
DISPLAY 1.021277 (-2800 4375);
PAINT ORANGE (-2800 4375);
DISPLAY INVISIBLE (-2800 4375);
FORCEPROP 2 LAST ROOM MIO_CHASSIS
J 0
(-2800 4325);
DISPLAY 1.021277 (-2800 4325);
PAINT ORANGE (-2800 4325);
DISPLAY INVISIBLE (-2800 4325);
FORCEPROP 1 LAST PATH I13
J 0
(-2800 4325);
DISPLAY 0.978723 (-2800 4325);
PAINT WHITE (-2800 4325);
DISPLAY INVISIBLE (-2800 4325);
FORCEPROP 0 LAST SEC 1
J 0
(-2800 4325);
DISPLAY 0.680851 (-2800 4325);
PAINT MONO (-2800 4325);
DISPLAY INVISIBLE (-2800 4325);
FORCEPROP 2 LAST CDS_LOCATION R1L26
J 0
(-2800 4225);
DISPLAY 0.617021 (-2800 4225);
PAINT AQUA (-2800 4225);
DISPLAY INVISIBLE (-2800 4225);
FORCEPROP 2 LAST CDS_LIB mstr_discrete
J 0
(-2750 4175);
PAINT ORANGE (-2750 4175);
DISPLAY INVISIBLE (-2750 4175);
FORCEADD OFFPAGE..2
(-1825 4175);
FORCEPROP 2 LAST $XR2 190 
J 0
(-1396 4175);
DISPLAY 0.638298 (-1396 4175);
PAINT MONO (-1396 4175);
FORCEPROP 2 LAST $XR1 145 
J 0
(-1516 4175);
DISPLAY 0.638298 (-1516 4175);
PAINT MONO (-1516 4175);
FORCEPROP 2 LAST $XR0 119 
J 0
(-1636 4175);
DISPLAY 0.638298 (-1636 4175);
PAINT MONO (-1636 4175);
FORCEPROP 1 LAST COMMENT_BODY TRUE
J 0
(-1870 4080);
DISPLAY 0.872340 (-1870 4080);
PAINT GREEN (-1870 4080);
DISPLAY INVISIBLE (-1870 4080);
FORCEPROP 1 LAST OFFPAGE TRUE
J 0
(-1500 4050);
DISPLAY 0.872340 (-1500 4050);
PAINT GREEN (-1500 4050);
DISPLAY INVISIBLE (-1500 4050);
FORCEPROP 2 LAST PATH I14
J 0
(-1775 4250);
DISPLAY 1.021277 (-1775 4250);
PAINT ORANGE (-1775 4250);
DISPLAY INVISIBLE (-1775 4250);
FORCEPROP 2 LAST CDS_LIB mstr_standard
J 0
(-1825 4175);
PAINT ORANGE (-1825 4175);
DISPLAY INVISIBLE (-1825 4175);
FORCEADD TTL2G14..1
(-3675 2775);
FORCEPROP 2 LASTPIN (-3525 2775) $PN 4
J 0
(-3515 2785);
DISPLAY 0.617021 (-3515 2785);
PAINT ORANGE (-3515 2785);
FORCEPROP 1 LAST POWER_GROUP VCC=P3V3_STBY;GND=GND
J 1
(-3525 2535);
DISPLAY 0.617021 (-3525 2535);
PAINT ORANGE (-3525 2535);
FORCEPROP 1 LAST PART_NUMBER D18476-001
J 0
(-3725 2640);
DISPLAY 0.617021 (-3725 2640);
PAINT BLUE (-3725 2640);
FORCEPROP 1 LAST VALUE 74LVC2G14
J 0
(-3725 2875);
DISPLAY 0.617021 (-3725 2875);
PAINT SKYBLUE (-3725 2875);
FORCEPROP 1 LAST LOCATION U9A3
J 0
(-3725 2975);
DISPLAY 0.617021 (-3725 2975);
PAINT AQUA (-3725 2975);
FORCEPROP 1 LAST MATERIAL IC
J 0
(-3725 2925);
DISPLAY 0.617021 (-3725 2925);
PAINT SKYBLUE (-3725 2925);
FORCEPROP 2 LASTPIN (-3775 2775) $PN 3
J 2
(-3785 2785);
DISPLAY 0.617021 (-3785 2785);
PAINT ORANGE (-3785 2785);
FORCEPROP 2 LAST BOM_COST MIO_CHASSIS
J 0
(-3725 3075);
DISPLAY 1.021277 (-3725 3075);
PAINT ORANGE (-3725 3075);
DISPLAY INVISIBLE (-3725 3075);
FORCEPROP 2 LAST ROOM MIO_CHASSIS
J 0
(-3725 3025);
DISPLAY 1.021277 (-3725 3025);
PAINT ORANGE (-3725 3025);
DISPLAY INVISIBLE (-3725 3025);
FORCEPROP 1 LAST PATH I15
J 0
(-3625 2825);
DISPLAY 0.978723 (-3625 2825);
PAINT WHITE (-3625 2825);
DISPLAY INVISIBLE (-3625 2825);
FORCEPROP 2 LAST CDS_LOCATION U9A3
J 0
(-3725 2975);
DISPLAY 0.617021 (-3725 2975);
PAINT AQUA (-3725 2975);
DISPLAY INVISIBLE (-3725 2975);
FORCEPROP 2 LAST SEC 2
J 0
(-3725 3025);
DISPLAY 0.680851 (-3725 3025);
PAINT MONO (-3725 3025);
DISPLAY INVISIBLE (-3725 3025);
FORCEPROP 2 LAST SEC_TYPE SMLF
J 0
(-3725 3025);
DISPLAY 1.021277 (-3725 3025);
PAINT ORANGE (-3725 3025);
DISPLAY INVISIBLE (-3725 3025);
FORCEPROP 1 LAST PACK_TYPE SMLF
J 0
(-3725 3025);
DISPLAY 0.978723 (-3725 3025);
PAINT SKYBLUE (-3725 3025);
DISPLAY INVISIBLE (-3725 3025);
FORCEPROP 2 LAST CDS_LIB mstr_ttl
J 0
(-3675 2775);
PAINT ORANGE (-3675 2775);
DISPLAY INVISIBLE (-3675 2775);
FORCEADD TTL2G14..1
(-4625 2775);
FORCEPROP 1 LAST POWER_GROUP VCC=P3V3_STBY;GND=GND
J 1
(-4275 2585);
DISPLAY 0.617021 (-4275 2585);
PAINT ORANGE (-4275 2585);
FORCEPROP 2 LASTPIN (-4475 2775) $PN 6
J 0
(-4465 2785);
DISPLAY 0.617021 (-4465 2785);
PAINT ORANGE (-4465 2785);
FORCEPROP 1 LAST LOCATION U9A3
J 0
(-4675 2975);
DISPLAY 0.617021 (-4675 2975);
PAINT AQUA (-4675 2975);
FORCEPROP 1 LAST PART_NUMBER D18476-001
J 0
(-4675 2640);
DISPLAY 0.617021 (-4675 2640);
PAINT BLUE (-4675 2640);
FORCEPROP 1 LAST VALUE 74LVC2G14
J 0
(-4675 2875);
DISPLAY 0.617021 (-4675 2875);
PAINT SKYBLUE (-4675 2875);
FORCEPROP 1 LAST MATERIAL IC
J 0
(-4675 2925);
DISPLAY 0.617021 (-4675 2925);
PAINT SKYBLUE (-4675 2925);
FORCEPROP 2 LASTPIN (-4725 2775) $PN 1
J 2
(-4735 2785);
DISPLAY 0.617021 (-4735 2785);
PAINT ORANGE (-4735 2785);
FORCEPROP 2 LAST BOM_COST MIO_CHASSIS
J 0
(-4675 3075);
DISPLAY 1.021277 (-4675 3075);
PAINT ORANGE (-4675 3075);
DISPLAY INVISIBLE (-4675 3075);
FORCEPROP 1 LAST PATH I18
J 0
(-4575 2825);
DISPLAY 0.978723 (-4575 2825);
PAINT WHITE (-4575 2825);
DISPLAY INVISIBLE (-4575 2825);
FORCEPROP 1 LAST PACK_TYPE SMLF
J 0
(-4675 3025);
DISPLAY 0.978723 (-4675 3025);
PAINT SKYBLUE (-4675 3025);
DISPLAY INVISIBLE (-4675 3025);
FORCEPROP 2 LAST SEC_TYPE SMLF
J 0
(-4675 3025);
DISPLAY 1.021277 (-4675 3025);
PAINT ORANGE (-4675 3025);
DISPLAY INVISIBLE (-4675 3025);
FORCEPROP 2 LAST CDS_LIB mstr_ttl
J 0
(-4625 2775);
PAINT ORANGE (-4625 2775);
DISPLAY INVISIBLE (-4625 2775);
FORCEPROP 2 LAST SEC 1
J 0
(-4675 3025);
DISPLAY 0.680851 (-4675 3025);
PAINT MONO (-4675 3025);
DISPLAY INVISIBLE (-4675 3025);
FORCEPROP 2 LAST CDS_LOCATION U9A3
J 0
(-4675 2975);
DISPLAY 0.617021 (-4675 2975);
PAINT AQUA (-4675 2975);
DISPLAY INVISIBLE (-4675 2975);
FORCEPROP 2 LAST ROOM MIO_CHASSIS
J 0
(-4675 3025);
DISPLAY 1.021277 (-4675 3025);
PAINT ORANGE (-4675 3025);
DISPLAY INVISIBLE (-4675 3025);
FORCEADD CAP_A..1
(-4925 2550);
FORCEPROP 1 LAST PART_NUMBER D97712-004
J 0
(-4875 2400);
DISPLAY 0.617021 (-4875 2400);
PAINT BLUE (-4875 2400);
FORCEPROP 1 LAST LOCATION C1L10
J 0
(-4875 2650);
DISPLAY 0.617021 (-4875 2650);
PAINT AQUA (-4875 2650);
FORCEPROP 1 LAST VALUE 1.0UF
J 0
(-4875 2600);
DISPLAY 0.617021 (-4875 2600);
PAINT SKYBLUE (-4875 2600);
FORCEPROP 1 LASTPIN (-4925 2650) $PN 1
J 0
(-4915 2630);
DISPLAY 0.617021 (-4915 2630);
PAINT ORANGE (-4915 2630);
FORCEPROP 1 LAST VOLTAGE 6.3V
J 0
(-4875 2550);
DISPLAY 0.617021 (-4875 2550);
PAINT SKYBLUE (-4875 2550);
FORCEPROP 1 LAST TOLERANCE 10%
J 0
(-4875 2500);
DISPLAY 0.617021 (-4875 2500);
PAINT SKYBLUE (-4875 2500);
FORCEPROP 1 LAST MATERIAL X6S
J 0
(-4875 2450);
DISPLAY 0.617021 (-4875 2450);
PAINT SKYBLUE (-4875 2450);
FORCEPROP 1 LASTPIN (-4925 2450) $PN 2
J 0
(-4915 2430);
DISPLAY 0.617021 (-4915 2430);
PAINT ORANGE (-4915 2430);
FORCEPROP 1 LAST PACK_TYPE 0402V
J 0
(-4875 2350);
DISPLAY 0.617021 (-4875 2350);
PAINT SKYBLUE (-4875 2350);
FORCEPROP 2 LAST SEC 1
J 0
(-4875 2700);
DISPLAY 0.680851 (-4875 2700);
PAINT MONO (-4875 2700);
DISPLAY INVISIBLE (-4875 2700);
FORCEPROP 1 LAST PATH I19
J 0
(-4875 2700);
DISPLAY 0.978723 (-4875 2700);
PAINT WHITE (-4875 2700);
DISPLAY INVISIBLE (-4875 2700);
FORCEPROP 2 LAST ROOM MIO_CHASSIS
J 0
(-4875 2700);
DISPLAY 1.021277 (-4875 2700);
PAINT ORANGE (-4875 2700);
DISPLAY INVISIBLE (-4875 2700);
FORCEPROP 2 LAST BOM_COST MIO_CHASSIS
J 0
(-4875 2750);
DISPLAY 1.021277 (-4875 2750);
PAINT ORANGE (-4875 2750);
DISPLAY INVISIBLE (-4875 2750);
FORCEPROP 2 LAST CDS_SEC 1
J 0
(-4875 2700);
PAINT ORANGE (-4875 2700);
DISPLAY INVISIBLE (-4875 2700);
FORCEPROP 2 LAST SEC_TYPE 0402V
J 0
(-4875 2750);
DISPLAY 1.021277 (-4875 2750);
PAINT ORANGE (-4875 2750);
DISPLAY INVISIBLE (-4875 2750);
FORCEPROP 2 LAST CDS_LOCATION C1L10
J 0
(-4875 2650);
DISPLAY 0.617021 (-4875 2650);
PAINT AQUA (-4875 2650);
DISPLAY INVISIBLE (-4875 2650);
FORCEPROP 2 LAST CDS_LIB dev_discrete
J 0
(-4925 2550);
PAINT ORANGE (-4925 2550);
DISPLAY INVISIBLE (-4925 2550);
FORCEADD GND..1
(-4925 2275);
FORCEPROP 3 LASTPIN (-4925 2325) SIG_NAME GND\g
J 0
(-4915 2335);
DISPLAY 0.659574 (-4915 2335);
PAINT MONO (-4915 2335);
DISPLAY INVISIBLE (-4915 2335);
FORCEPROP 1 LAST HDL_POWER GND
J 0
(-4925 2425);
DISPLAY 0.872340 (-4925 2425);
PAINT GREEN (-4925 2425);
DISPLAY INVISIBLE (-4925 2425);
FORCEPROP 1 LAST BODY_TYPE PLUMBING
J 0
(-4970 2232);
DISPLAY 0.340426 (-4970 2232);
PAINT GREEN (-4970 2232);
DISPLAY INVISIBLE (-4970 2232);
FORCEPROP 1 LAST SIZE 1B
J 0
(-4850 2225);
DISPLAY 0.872340 (-4850 2225);
PAINT AQUA (-4850 2225);
DISPLAY INVISIBLE (-4850 2225);
FORCEPROP 1 LAST PATH I20
J 0
(-4850 2275);
DISPLAY 0.872340 (-4850 2275);
PAINT AQUA (-4850 2275);
DISPLAY INVISIBLE (-4850 2275);
FORCEPROP 2 LAST CDS_LIB mstr_symbols
J 0
(-4925 2275);
PAINT ORANGE (-4925 2275);
DISPLAY INVISIBLE (-4925 2275);
FORCEPROP 1 LAST VOLTAGE 0.0V
J 0
(-4970 2232);
DISPLAY 0.340426 (-4970 2232);
PAINT SKYBLUE (-4970 2232);
DISPLAY INVISIBLE (-4970 2232);
FORCEADD P3V3_STBY..1
(-5875 3400);
FORCEPROP 3 LASTPIN (-5875 3350) SIG_NAME P3V3_STBY\g
J 0
(-5865 3360);
DISPLAY 0.659574 (-5865 3360);
PAINT MONO (-5865 3360);
DISPLAY INVISIBLE (-5865 3360);
FORCEPROP 1 LAST HDL_POWER P3V3_STBY
J 0
(-6175 3275);
DISPLAY 0.872340 (-6175 3275);
PAINT ORANGE (-6175 3275);
DISPLAY INVISIBLE (-6175 3275);
FORCEPROP 1 LAST BODY_TYPE PLUMBING
J 0
(-5920 3357);
DISPLAY 0.340426 (-5920 3357);
PAINT GREEN (-5920 3357);
DISPLAY INVISIBLE (-5920 3357);
FORCEPROP 2 LAST CDS_LIB mstr_symbols
J 0
(-5875 3400);
PAINT ORANGE (-5875 3400);
DISPLAY INVISIBLE (-5875 3400);
FORCEPROP 1 LAST SIZE 1B
J 0
(-5830 3422);
DISPLAY 0.340426 (-5830 3422);
PAINT GREEN (-5830 3422);
DISPLAY INVISIBLE (-5830 3422);
FORCEPROP 1 LAST PATH I21
J 0
(-5830 3402);
DISPLAY 0.340426 (-5830 3402);
PAINT GREEN (-5830 3402);
DISPLAY INVISIBLE (-5830 3402);
FORCEPROP 1 LAST VOLTAGE 3.3V
J 0
(-5920 3357);
DISPLAY 0.340426 (-5920 3357);
PAINT SKYBLUE (-5920 3357);
DISPLAY INVISIBLE (-5920 3357);
FORCEADD RES..1
(-5600 2775);
FORCEPROP 1 LAST TOLERANCE 1%
J 0
(-5600 2675);
DISPLAY 0.617021 (-5600 2675);
PAINT SKYBLUE (-5600 2675);
FORCEPROP 1 LAST PACK_TYPE 0402
J 0
(-5350 2625);
DISPLAY 0.617021 (-5350 2625);
PAINT SKYBLUE (-5350 2625);
FORCEPROP 1 LASTPIN (-5500 2775) $PN 2
J 0
(-5538 2787);
DISPLAY 0.617021 (-5538 2787);
PAINT ORANGE (-5538 2787);
FORCEPROP 1 LAST LOCATION R1L22
J 0
(-5650 2825);
DISPLAY 0.617021 (-5650 2825);
PAINT AQUA (-5650 2825);
FORCEPROP 1 LAST PART_NUMBER G21796-004
J 0
(-5650 2875);
DISPLAY 0.617021 (-5650 2875);
PAINT BLUE (-5650 2875);
FORCEPROP 1 LAST WATTAGE 1/16W
J 2
(-5625 2625);
DISPLAY 0.617021 (-5625 2625);
PAINT SKYBLUE (-5625 2625);
FORCEPROP 1 LASTPIN (-5700 2775) $PN 1
J 0
(-5688 2787);
DISPLAY 0.617021 (-5688 2787);
PAINT ORANGE (-5688 2787);
FORCEPROP 1 LAST MATERIAL CHIP
J 0
(-5600 2625);
DISPLAY 0.617021 (-5600 2625);
PAINT SKYBLUE (-5600 2625);
FORCEPROP 1 LAST VALUE 200.0
J 2
(-5625 2675);
DISPLAY 0.617021 (-5625 2675);
PAINT SKYBLUE (-5625 2675);
FORCEPROP 2 LAST CDS_LIB mstr_discrete
J 0
(-5600 2775);
PAINT ORANGE (-5600 2775);
DISPLAY INVISIBLE (-5600 2775);
FORCEPROP 2 LAST BOM_COST MIO_CHASSIS
J 0
(-5650 2975);
DISPLAY 1.021277 (-5650 2975);
PAINT ORANGE (-5650 2975);
DISPLAY INVISIBLE (-5650 2975);
FORCEPROP 2 LAST SEC_TYPE 0402
J 0
(-5650 2975);
DISPLAY 1.021277 (-5650 2975);
PAINT ORANGE (-5650 2975);
DISPLAY INVISIBLE (-5650 2975);
FORCEPROP 0 LAST SEC 1
J 0
(-5650 2925);
DISPLAY 0.680851 (-5650 2925);
PAINT MONO (-5650 2925);
DISPLAY INVISIBLE (-5650 2925);
FORCEPROP 2 LAST CDS_LOCATION R1L22
J 0
(-5650 2825);
DISPLAY 0.617021 (-5650 2825);
PAINT AQUA (-5650 2825);
DISPLAY INVISIBLE (-5650 2825);
FORCEPROP 1 LAST PATH I22
J 0
(-5650 2925);
DISPLAY 0.978723 (-5650 2925);
PAINT WHITE (-5650 2925);
DISPLAY INVISIBLE (-5650 2925);
FORCEPROP 2 LAST ROOM MIO_CHASSIS
J 0
(-5650 2925);
DISPLAY 1.021277 (-5650 2925);
PAINT ORANGE (-5650 2925);
DISPLAY INVISIBLE (-5650 2925);
FORCEADD RES..2
(-5875 3075);
FORCEPROP 1 LAST LOCATION R1L19
J 0
(-5830 3200);
DISPLAY 0.617021 (-5830 3200);
PAINT AQUA (-5830 3200);
FORCEPROP 1 LAST VALUE 4.75K
J 0
(-5830 3150);
DISPLAY 0.617021 (-5830 3150);
PAINT SKYBLUE (-5830 3150);
FORCEPROP 1 LAST TOLERANCE 1%
J 0
(-5830 3100);
DISPLAY 0.617021 (-5830 3100);
PAINT SKYBLUE (-5830 3100);
FORCEPROP 1 LASTPIN (-5875 3175) $PN 1
J 0
(-5870 3137);
DISPLAY 0.617021 (-5870 3137);
PAINT ORANGE (-5870 3137);
FORCEPROP 1 LAST WATTAGE 1/16W
J 0
(-5835 3050);
DISPLAY 0.617021 (-5835 3050);
PAINT SKYBLUE (-5835 3050);
FORCEPROP 1 LAST PART_NUMBER G21796-072
J 0
(-5835 2950);
DISPLAY 0.617021 (-5835 2950);
PAINT BLUE (-5835 2950);
FORCEPROP 1 LAST MATERIAL EMPTY
J 0
(-5835 3000);
DISPLAY 0.617021 (-5835 3000);
PAINT RED (-5835 3000);
FORCEPROP 1 LAST PACK_TYPE 0402
J 0
(-5835 2900);
DISPLAY 0.617021 (-5835 2900);
PAINT SKYBLUE (-5835 2900);
FORCEPROP 1 LASTPIN (-5875 2975) $PN 2
J 0
(-5870 2985);
DISPLAY 0.617021 (-5870 2985);
PAINT ORANGE (-5870 2985);
FORCEPROP 2 LAST BOM_COST MIO_CHASSIS
J 0
(-5825 3300);
DISPLAY 1.021277 (-5825 3300);
PAINT ORANGE (-5825 3300);
DISPLAY INVISIBLE (-5825 3300);
FORCEPROP 2 LAST SEC_TYPE 0402
J 0
(-5825 3300);
DISPLAY 1.021277 (-5825 3300);
PAINT ORANGE (-5825 3300);
DISPLAY INVISIBLE (-5825 3300);
FORCEPROP 0 LAST SEC 1
J 0
(-5825 3250);
DISPLAY 0.680851 (-5825 3250);
PAINT MONO (-5825 3250);
DISPLAY INVISIBLE (-5825 3250);
FORCEPROP 1 LAST PATH I24
J 0
(-5825 3250);
DISPLAY 0.978723 (-5825 3250);
PAINT WHITE (-5825 3250);
DISPLAY INVISIBLE (-5825 3250);
FORCEPROP 2 LAST ROOM MIO_CHASSIS
J 0
(-5825 3250);
DISPLAY 1.021277 (-5825 3250);
PAINT ORANGE (-5825 3250);
DISPLAY INVISIBLE (-5825 3250);
FORCEPROP 2 LAST CDS_LOCATION R1L19
J 0
(-5830 3200);
DISPLAY 0.617021 (-5830 3200);
PAINT AQUA (-5830 3200);
DISPLAY INVISIBLE (-5830 3200);
FORCEPROP 2 LAST CDS_LIB mstr_discrete
J 0
(-5875 3075);
PAINT ORANGE (-5875 3075);
DISPLAY INVISIBLE (-5875 3075);
FORCEADD GND..1
(-7625 2250);
FORCEPROP 3 LASTPIN (-7625 2300) SIG_NAME GND\g
J 0
(-7615 2310);
DISPLAY 0.659574 (-7615 2310);
PAINT MONO (-7615 2310);
DISPLAY INVISIBLE (-7615 2310);
FORCEPROP 1 LAST HDL_POWER GND
J 0
(-7625 2400);
DISPLAY 0.872340 (-7625 2400);
PAINT GREEN (-7625 2400);
DISPLAY INVISIBLE (-7625 2400);
FORCEPROP 1 LAST BODY_TYPE PLUMBING
J 0
(-7670 2207);
DISPLAY 0.340426 (-7670 2207);
PAINT GREEN (-7670 2207);
DISPLAY INVISIBLE (-7670 2207);
FORCEPROP 1 LAST PATH I27
J 0
(-7550 2250);
DISPLAY 0.872340 (-7550 2250);
PAINT AQUA (-7550 2250);
DISPLAY INVISIBLE (-7550 2250);
FORCEPROP 2 LAST CDS_LIB mstr_symbols
J 0
(-7625 2250);
PAINT ORANGE (-7625 2250);
DISPLAY INVISIBLE (-7625 2250);
FORCEPROP 1 LAST SIZE 1B
J 0
(-7550 2200);
DISPLAY 0.872340 (-7550 2200);
PAINT AQUA (-7550 2200);
DISPLAY INVISIBLE (-7550 2200);
FORCEPROP 1 LAST VOLTAGE 0.0V
J 0
(-7670 2207);
DISPLAY 0.340426 (-7670 2207);
PAINT SKYBLUE (-7670 2207);
DISPLAY INVISIBLE (-7670 2207);
FORCEADD OFFPAGE..1
(-7550 1925);
FORCEPROP 2 LAST $XR2 190 
J 0
(-8042 1875);
DISPLAY 0.638298 (-8042 1875);
PAINT MONO (-8042 1875);
FORCEPROP 2 LAST $XR3 247 
J 0
(-8042 1925);
DISPLAY 0.638298 (-8042 1925);
PAINT MONO (-8042 1925);
FORCEPROP 2 LAST $XR0 111 
J 0
(-7802 1925);
DISPLAY 0.638298 (-7802 1925);
PAINT MONO (-7802 1925);
FORCEPROP 2 LAST $XR1 155 
J 0
(-7922 1925);
DISPLAY 0.638298 (-7922 1925);
PAINT MONO (-7922 1925);
FORCEPROP 1 LAST COMMENT_BODY TRUE
J 0
(-7425 1825);
DISPLAY 0.872340 (-7425 1825);
PAINT GREEN (-7425 1825);
DISPLAY INVISIBLE (-7425 1825);
FORCEPROP 1 LAST OFFPAGE TRUE
J 0
(-7225 1800);
DISPLAY 0.872340 (-7225 1800);
PAINT GREEN (-7225 1800);
DISPLAY INVISIBLE (-7225 1800);
FORCEPROP 2 LAST CDS_LIB mstr_standard
J 0
(-7550 1925);
PAINT ORANGE (-7550 1925);
DISPLAY INVISIBLE (-7550 1925);
FORCEPROP 2 LAST PATH I28
J 0
(-7500 2000);
DISPLAY 1.021277 (-7500 2000);
PAINT ORANGE (-7500 2000);
DISPLAY INVISIBLE (-7500 2000);
FORCEADD GND..1
(-7675 3650);
FORCEPROP 3 LASTPIN (-7675 3700) SIG_NAME GND\g
J 0
(-7665 3710);
DISPLAY 0.659574 (-7665 3710);
PAINT MONO (-7665 3710);
DISPLAY INVISIBLE (-7665 3710);
FORCEPROP 1 LAST HDL_POWER GND
J 0
(-7675 3800);
DISPLAY 0.872340 (-7675 3800);
PAINT GREEN (-7675 3800);
DISPLAY INVISIBLE (-7675 3800);
FORCEPROP 1 LAST BODY_TYPE PLUMBING
J 0
(-7720 3607);
DISPLAY 0.340426 (-7720 3607);
PAINT GREEN (-7720 3607);
DISPLAY INVISIBLE (-7720 3607);
FORCEPROP 2 LAST CDS_LIB mstr_symbols
J 0
(-7675 3650);
PAINT ORANGE (-7675 3650);
DISPLAY INVISIBLE (-7675 3650);
FORCEPROP 1 LAST PATH I3
J 0
(-7600 3650);
DISPLAY 0.872340 (-7600 3650);
PAINT AQUA (-7600 3650);
DISPLAY INVISIBLE (-7600 3650);
FORCEPROP 1 LAST SIZE 1B
J 0
(-7600 3600);
DISPLAY 0.872340 (-7600 3600);
PAINT AQUA (-7600 3600);
DISPLAY INVISIBLE (-7600 3600);
FORCEPROP 1 LAST VOLTAGE 0.0V
J 0
(-7720 3607);
DISPLAY 0.340426 (-7720 3607);
PAINT SKYBLUE (-7720 3607);
DISPLAY INVISIBLE (-7720 3607);
FORCEADD RES..1
(-2225 2775);
FORCEPROP 1 LAST VALUE 100.0
J 2
(-2250 2675);
DISPLAY 0.617021 (-2250 2675);
PAINT SKYBLUE (-2250 2675);
FORCEPROP 1 LAST MATERIAL CHIP
J 0
(-2225 2625);
DISPLAY 0.617021 (-2225 2625);
PAINT SKYBLUE (-2225 2625);
FORCEPROP 1 LAST WATTAGE 1/16W
J 2
(-2250 2625);
DISPLAY 0.617021 (-2250 2625);
PAINT SKYBLUE (-2250 2625);
FORCEPROP 1 LAST PART_NUMBER G21796-017
J 0
(-2275 2875);
DISPLAY 0.617021 (-2275 2875);
PAINT BLUE (-2275 2875);
FORCEPROP 1 LAST LOCATION R9A9
J 0
(-2275 2825);
DISPLAY 0.617021 (-2275 2825);
PAINT AQUA (-2275 2825);
FORCEPROP 1 LAST TOLERANCE 1%
J 0
(-2225 2675);
DISPLAY 0.617021 (-2225 2675);
PAINT SKYBLUE (-2225 2675);
FORCEPROP 1 LASTPIN (-2125 2775) $PN 2
J 0
(-2163 2787);
DISPLAY 0.617021 (-2163 2787);
PAINT ORANGE (-2163 2787);
FORCEPROP 1 LASTPIN (-2325 2775) $PN 1
J 0
(-2313 2787);
DISPLAY 0.617021 (-2313 2787);
PAINT ORANGE (-2313 2787);
FORCEPROP 1 LAST PACK_TYPE 0402
J 0
(-1975 2625);
DISPLAY 0.617021 (-1975 2625);
PAINT SKYBLUE (-1975 2625);
FORCEPROP 2 LAST ROOM MIO_CHASSIS
J 0
(-2275 2925);
DISPLAY 1.021277 (-2275 2925);
PAINT ORANGE (-2275 2925);
DISPLAY INVISIBLE (-2275 2925);
FORCEPROP 1 LAST PATH I35
J 0
(-2275 2925);
DISPLAY 0.978723 (-2275 2925);
PAINT WHITE (-2275 2925);
DISPLAY INVISIBLE (-2275 2925);
FORCEPROP 2 LAST CDS_LOCATION R9A9
J 0
(-2275 2825);
DISPLAY 0.617021 (-2275 2825);
PAINT AQUA (-2275 2825);
DISPLAY INVISIBLE (-2275 2825);
FORCEPROP 0 LAST SEC 1
J 0
(-2275 2925);
DISPLAY 0.680851 (-2275 2925);
PAINT MONO (-2275 2925);
DISPLAY INVISIBLE (-2275 2925);
FORCEPROP 2 LAST BOM_COST MIO_CHASSIS
J 0
(-2275 2975);
DISPLAY 1.021277 (-2275 2975);
PAINT ORANGE (-2275 2975);
DISPLAY INVISIBLE (-2275 2975);
FORCEPROP 2 LAST SEC_TYPE 0402
J 0
(-2275 2975);
DISPLAY 1.021277 (-2275 2975);
PAINT ORANGE (-2275 2975);
DISPLAY INVISIBLE (-2275 2975);
FORCEPROP 2 LAST CDS_LIB mstr_discrete
J 0
(-2225 2775);
PAINT ORANGE (-2225 2775);
DISPLAY INVISIBLE (-2225 2775);
FORCEADD OFFPAGE..2
(-1450 2775);
FORCEPROP 2 LAST $XR1 145 
J 0
(-1141 2775);
DISPLAY 0.638298 (-1141 2775);
PAINT MONO (-1141 2775);
FORCEPROP 2 LAST $XR0 119 
J 0
(-1261 2775);
DISPLAY 0.638298 (-1261 2775);
PAINT MONO (-1261 2775);
FORCEPROP 1 LAST COMMENT_BODY TRUE
J 0
(-1495 2680);
DISPLAY 0.872340 (-1495 2680);
PAINT GREEN (-1495 2680);
DISPLAY INVISIBLE (-1495 2680);
FORCEPROP 1 LAST OFFPAGE TRUE
J 0
(-1125 2650);
DISPLAY 0.872340 (-1125 2650);
PAINT GREEN (-1125 2650);
DISPLAY INVISIBLE (-1125 2650);
FORCEPROP 2 LAST PATH I36
J 0
(-1400 2850);
DISPLAY 1.021277 (-1400 2850);
PAINT ORANGE (-1400 2850);
DISPLAY INVISIBLE (-1400 2850);
FORCEPROP 2 LAST CDS_LIB mstr_standard
J 0
(-1450 2775);
PAINT ORANGE (-1450 2775);
DISPLAY INVISIBLE (-1450 2775);
FORCEADD CAP_A..1
(-4400 4675);
FORCEPROP 1 LAST PART_NUMBER A36096-030
J 0
(-4350 4525);
DISPLAY 0.617021 (-4350 4525);
PAINT BLUE (-4350 4525);
FORCEPROP 1 LAST LOCATION C1L17
J 0
(-4350 4775);
DISPLAY 0.617021 (-4350 4775);
PAINT AQUA (-4350 4775);
FORCEPROP 1 LAST VALUE 0.1UF
J 0
(-4350 4725);
DISPLAY 0.617021 (-4350 4725);
PAINT SKYBLUE (-4350 4725);
FORCEPROP 1 LAST TOLERANCE 10%
J 0
(-4350 4625);
DISPLAY 0.617021 (-4350 4625);
PAINT SKYBLUE (-4350 4625);
FORCEPROP 1 LAST VOLTAGE 16V
J 0
(-4350 4675);
DISPLAY 0.617021 (-4350 4675);
PAINT SKYBLUE (-4350 4675);
FORCEPROP 1 LASTPIN (-4400 4775) $PN 1
J 0
(-4390 4755);
DISPLAY 0.617021 (-4390 4755);
PAINT ORANGE (-4390 4755);
FORCEPROP 1 LAST PACK_TYPE 0402V
J 0
(-4350 4475);
DISPLAY 0.617021 (-4350 4475);
PAINT SKYBLUE (-4350 4475);
FORCEPROP 1 LAST MATERIAL X7R
J 0
(-4350 4575);
DISPLAY 0.617021 (-4350 4575);
PAINT SKYBLUE (-4350 4575);
FORCEPROP 1 LASTPIN (-4400 4575) $PN 2
J 0
(-4390 4555);
DISPLAY 0.617021 (-4390 4555);
PAINT ORANGE (-4390 4555);
FORCEPROP 1 LAST PATH I37
J 0
(-4350 4825);
DISPLAY 0.978723 (-4350 4825);
PAINT WHITE (-4350 4825);
DISPLAY INVISIBLE (-4350 4825);
FORCEPROP 2 LAST ROOM MIO_CHASSIS
J 0
(-4350 4825);
DISPLAY 1.021277 (-4350 4825);
PAINT ORANGE (-4350 4825);
DISPLAY INVISIBLE (-4350 4825);
FORCEPROP 2 LAST CDS_LOCATION C1L17
J 0
(-4350 4775);
DISPLAY 0.617021 (-4350 4775);
PAINT AQUA (-4350 4775);
DISPLAY INVISIBLE (-4350 4775);
FORCEPROP 2 LAST BOM_COST MIO_CHASSIS
J 0
(-4350 4875);
DISPLAY 1.021277 (-4350 4875);
PAINT ORANGE (-4350 4875);
DISPLAY INVISIBLE (-4350 4875);
FORCEPROP 2 LAST CDS_SEC 1
J 0
(-4350 4825);
PAINT ORANGE (-4350 4825);
DISPLAY INVISIBLE (-4350 4825);
FORCEPROP 2 LAST SEC_TYPE 0402V
J 0
(-4350 4875);
DISPLAY 1.021277 (-4350 4875);
PAINT ORANGE (-4350 4875);
DISPLAY INVISIBLE (-4350 4875);
FORCEPROP 2 LAST SEC 1
J 0
(-4350 4825);
DISPLAY 0.680851 (-4350 4825);
PAINT MONO (-4350 4825);
DISPLAY INVISIBLE (-4350 4825);
FORCEPROP 2 LAST CDS_LIB dev_discrete
J 0
(-4400 4675);
PAINT ORANGE (-4400 4675);
DISPLAY INVISIBLE (-4400 4675);
FORCEADD CAP_A..1
(-4500 3350);
FORCEPROP 1 LAST VALUE 0.1UF
J 0
(-4450 3400);
DISPLAY 0.617021 (-4450 3400);
PAINT SKYBLUE (-4450 3400);
FORCEPROP 1 LAST LOCATION C1L9
J 0
(-4450 3450);
DISPLAY 0.617021 (-4450 3450);
PAINT AQUA (-4450 3450);
FORCEPROP 1 LASTPIN (-4500 3450) $PN 1
J 0
(-4490 3430);
DISPLAY 0.617021 (-4490 3430);
PAINT ORANGE (-4490 3430);
FORCEPROP 1 LAST VOLTAGE 16V
J 0
(-4450 3350);
DISPLAY 0.617021 (-4450 3350);
PAINT SKYBLUE (-4450 3350);
FORCEPROP 1 LASTPIN (-4500 3250) $PN 2
J 0
(-4490 3230);
DISPLAY 0.617021 (-4490 3230);
PAINT ORANGE (-4490 3230);
FORCEPROP 1 LAST MATERIAL X7R
J 0
(-4450 3250);
DISPLAY 0.617021 (-4450 3250);
PAINT SKYBLUE (-4450 3250);
FORCEPROP 1 LAST TOLERANCE 10%
J 0
(-4450 3300);
DISPLAY 0.617021 (-4450 3300);
PAINT SKYBLUE (-4450 3300);
FORCEPROP 1 LAST PACK_TYPE 0402V
J 0
(-4450 3150);
DISPLAY 0.617021 (-4450 3150);
PAINT SKYBLUE (-4450 3150);
FORCEPROP 1 LAST PART_NUMBER A36096-030
J 0
(-4450 3200);
DISPLAY 0.617021 (-4450 3200);
PAINT BLUE (-4450 3200);
FORCEPROP 2 LAST BOM_COST MIO_CHASSIS
J 0
(-4450 3550);
DISPLAY 1.021277 (-4450 3550);
PAINT ORANGE (-4450 3550);
DISPLAY INVISIBLE (-4450 3550);
FORCEPROP 2 LAST SEC_TYPE 0402V
J 0
(-4450 3550);
DISPLAY 1.021277 (-4450 3550);
PAINT ORANGE (-4450 3550);
DISPLAY INVISIBLE (-4450 3550);
FORCEPROP 1 LAST PATH I38
J 0
(-4450 3500);
DISPLAY 0.978723 (-4450 3500);
PAINT WHITE (-4450 3500);
DISPLAY INVISIBLE (-4450 3500);
FORCEPROP 2 LAST ROOM MIO_CHASSIS
J 0
(-4450 3500);
DISPLAY 1.021277 (-4450 3500);
PAINT ORANGE (-4450 3500);
DISPLAY INVISIBLE (-4450 3500);
FORCEPROP 2 LAST CDS_LOCATION C1L9
J 0
(-4450 3450);
DISPLAY 0.617021 (-4450 3450);
PAINT AQUA (-4450 3450);
DISPLAY INVISIBLE (-4450 3450);
FORCEPROP 2 LAST CDS_LIB dev_discrete
J 0
(-4500 3350);
PAINT ORANGE (-4500 3350);
DISPLAY INVISIBLE (-4500 3350);
FORCEPROP 2 LAST CDS_SEC 1
J 0
(-4450 3500);
PAINT ORANGE (-4450 3500);
DISPLAY INVISIBLE (-4450 3500);
FORCEPROP 2 LAST SEC 1
J 0
(-4450 3500);
DISPLAY 0.680851 (-4450 3500);
PAINT MONO (-4450 3500);
DISPLAY INVISIBLE (-4450 3500);
FORCEADD RES..1
(-5650 4175);
FORCEPROP 1 LASTPIN (-5550 4175) $PN 2
J 0
(-5588 4187);
DISPLAY 0.617021 (-5588 4187);
PAINT ORANGE (-5588 4187);
FORCEPROP 1 LAST LOCATION R1L31
J 0
(-5700 4225);
DISPLAY 0.617021 (-5700 4225);
PAINT AQUA (-5700 4225);
FORCEPROP 1 LAST PART_NUMBER G21796-004
J 0
(-5700 4275);
DISPLAY 0.617021 (-5700 4275);
PAINT BLUE (-5700 4275);
FORCEPROP 1 LAST VALUE 200.0
J 2
(-5675 4075);
DISPLAY 0.617021 (-5675 4075);
PAINT SKYBLUE (-5675 4075);
FORCEPROP 1 LAST TOLERANCE 1%
J 0
(-5650 4075);
DISPLAY 0.617021 (-5650 4075);
PAINT SKYBLUE (-5650 4075);
FORCEPROP 1 LAST MATERIAL CHIP
J 0
(-5650 4025);
DISPLAY 0.617021 (-5650 4025);
PAINT SKYBLUE (-5650 4025);
FORCEPROP 1 LAST WATTAGE 1/16W
J 2
(-5675 4025);
DISPLAY 0.617021 (-5675 4025);
PAINT SKYBLUE (-5675 4025);
FORCEPROP 1 LASTPIN (-5750 4175) $PN 1
J 0
(-5738 4187);
DISPLAY 0.617021 (-5738 4187);
PAINT ORANGE (-5738 4187);
FORCEPROP 1 LAST PACK_TYPE 0402
J 0
(-5400 4025);
DISPLAY 0.617021 (-5400 4025);
PAINT SKYBLUE (-5400 4025);
FORCEPROP 2 LAST SEC 1
J 0
(-5700 4375);
DISPLAY 0.680851 (-5700 4375);
PAINT MONO (-5700 4375);
DISPLAY INVISIBLE (-5700 4375);
FORCEPROP 2 LAST BOM_COST MIO_CHASSIS
J 0
(-5700 4375);
DISPLAY 1.021277 (-5700 4375);
PAINT ORANGE (-5700 4375);
DISPLAY INVISIBLE (-5700 4375);
FORCEPROP 2 LAST SEC_TYPE 0402
J 0
(-5700 4375);
DISPLAY 1.021277 (-5700 4375);
PAINT ORANGE (-5700 4375);
DISPLAY INVISIBLE (-5700 4375);
FORCEPROP 1 LAST PATH I4
J 0
(-5700 4325);
DISPLAY 0.978723 (-5700 4325);
PAINT WHITE (-5700 4325);
DISPLAY INVISIBLE (-5700 4325);
FORCEPROP 2 LAST ROOM MIO_CHASSIS
J 0
(-5700 4325);
DISPLAY 1.021277 (-5700 4325);
PAINT ORANGE (-5700 4325);
DISPLAY INVISIBLE (-5700 4325);
FORCEPROP 2 LAST CDS_LOCATION R1L31
J 0
(-5700 4225);
DISPLAY 0.617021 (-5700 4225);
PAINT AQUA (-5700 4225);
DISPLAY INVISIBLE (-5700 4225);
FORCEPROP 2 LAST CDS_LIB mstr_discrete
J 0
(-5650 4175);
PAINT ORANGE (-5650 4175);
DISPLAY INVISIBLE (-5650 4175);
FORCEADD CAP_A..1
(-575 3500);
FORCEPROP 1 LAST LOCATION C9A3
J 0
(-525 3600);
DISPLAY 0.617021 (-525 3600);
PAINT AQUA (-525 3600);
FORCEPROP 1 LAST PART_NUMBER A36096-030
J 0
(-525 3350);
DISPLAY 0.617021 (-525 3350);
PAINT BLUE (-525 3350);
FORCEPROP 1 LAST VALUE 0.1UF
J 0
(-525 3550);
DISPLAY 0.617021 (-525 3550);
PAINT SKYBLUE (-525 3550);
FORCEPROP 1 LAST TOLERANCE 10%
J 0
(-525 3450);
DISPLAY 0.617021 (-525 3450);
PAINT SKYBLUE (-525 3450);
FORCEPROP 1 LAST PACK_TYPE 0402V
J 0
(-525 3300);
DISPLAY 0.617021 (-525 3300);
PAINT SKYBLUE (-525 3300);
FORCEPROP 1 LAST VOLTAGE 16V
J 0
(-525 3500);
DISPLAY 0.617021 (-525 3500);
PAINT SKYBLUE (-525 3500);
FORCEPROP 1 LAST MATERIAL X7R
J 0
(-525 3400);
DISPLAY 0.617021 (-525 3400);
PAINT SKYBLUE (-525 3400);
FORCEPROP 1 LASTPIN (-575 3600) $PN 1
J 0
(-565 3580);
DISPLAY 0.617021 (-565 3580);
PAINT ORANGE (-565 3580);
FORCEPROP 1 LASTPIN (-575 3400) $PN 2
J 0
(-565 3380);
DISPLAY 0.617021 (-565 3380);
PAINT ORANGE (-565 3380);
FORCEPROP 2 LAST SEC 1
J 0
(-525 3700);
DISPLAY 0.680851 (-525 3700);
PAINT MONO (-525 3700);
DISPLAY INVISIBLE (-525 3700);
FORCEPROP 2 LAST SEC_TYPE 0402V
J 0
(-525 3700);
DISPLAY 1.021277 (-525 3700);
PAINT ORANGE (-525 3700);
DISPLAY INVISIBLE (-525 3700);
FORCEPROP 2 LAST BOM_COST MIO_CHASSIS
J 0
(-525 3700);
DISPLAY 1.021277 (-525 3700);
PAINT ORANGE (-525 3700);
DISPLAY INVISIBLE (-525 3700);
FORCEPROP 2 LAST ROOM MIO_CHASSIS
J 0
(-525 3650);
DISPLAY 1.021277 (-525 3650);
PAINT ORANGE (-525 3650);
DISPLAY INVISIBLE (-525 3650);
FORCEPROP 1 LAST PATH I40
J 0
(-525 3650);
DISPLAY 0.978723 (-525 3650);
PAINT WHITE (-525 3650);
DISPLAY INVISIBLE (-525 3650);
FORCEPROP 2 LAST CDS_LOCATION C9A3
J 0
(-525 3600);
DISPLAY 0.617021 (-525 3600);
PAINT AQUA (-525 3600);
DISPLAY INVISIBLE (-525 3600);
FORCEPROP 2 LAST CDS_SEC 1
J 0
(-525 3650);
PAINT ORANGE (-525 3650);
DISPLAY INVISIBLE (-525 3650);
FORCEPROP 2 LAST CDS_LIB dev_discrete
J 0
(-575 3500);
PAINT ORANGE (-575 3500);
DISPLAY INVISIBLE (-575 3500);
FORCEADD GND..1
(-4500 3050);
FORCEPROP 3 LASTPIN (-4500 3100) SIG_NAME GND\g
J 0
(-4490 3110);
DISPLAY 0.659574 (-4490 3110);
PAINT MONO (-4490 3110);
DISPLAY INVISIBLE (-4490 3110);
FORCEPROP 1 LAST HDL_POWER GND
J 0
(-4500 3200);
DISPLAY 0.872340 (-4500 3200);
PAINT GREEN (-4500 3200);
DISPLAY INVISIBLE (-4500 3200);
FORCEPROP 1 LAST BODY_TYPE PLUMBING
J 0
(-4545 3007);
DISPLAY 0.340426 (-4545 3007);
PAINT GREEN (-4545 3007);
DISPLAY INVISIBLE (-4545 3007);
FORCEPROP 2 LAST CDS_LIB mstr_symbols
J 0
(-4500 3050);
PAINT ORANGE (-4500 3050);
DISPLAY INVISIBLE (-4500 3050);
FORCEPROP 1 LAST PATH I41
J 0
(-4425 3050);
DISPLAY 0.872340 (-4425 3050);
PAINT AQUA (-4425 3050);
DISPLAY INVISIBLE (-4425 3050);
FORCEPROP 1 LAST VOLTAGE 0.0V
J 0
(-4545 3007);
DISPLAY 0.340426 (-4545 3007);
PAINT SKYBLUE (-4545 3007);
DISPLAY INVISIBLE (-4545 3007);
FORCEPROP 1 LAST SIZE 1B
J 0
(-4425 3000);
DISPLAY 0.872340 (-4425 3000);
PAINT AQUA (-4425 3000);
DISPLAY INVISIBLE (-4425 3000);
FORCEADD GND..1
(-4400 4425);
FORCEPROP 3 LASTPIN (-4400 4475) SIG_NAME GND\g
J 0
(-4390 4485);
DISPLAY 0.659574 (-4390 4485);
PAINT MONO (-4390 4485);
DISPLAY INVISIBLE (-4390 4485);
FORCEPROP 1 LAST HDL_POWER GND
J 0
(-4400 4575);
DISPLAY 0.872340 (-4400 4575);
PAINT GREEN (-4400 4575);
DISPLAY INVISIBLE (-4400 4575);
FORCEPROP 1 LAST BODY_TYPE PLUMBING
J 0
(-4445 4382);
DISPLAY 0.340426 (-4445 4382);
PAINT GREEN (-4445 4382);
DISPLAY INVISIBLE (-4445 4382);
FORCEPROP 1 LAST PATH I42
J 0
(-4325 4425);
DISPLAY 0.872340 (-4325 4425);
PAINT AQUA (-4325 4425);
DISPLAY INVISIBLE (-4325 4425);
FORCEPROP 1 LAST SIZE 1B
J 0
(-4325 4375);
DISPLAY 0.872340 (-4325 4375);
PAINT AQUA (-4325 4375);
DISPLAY INVISIBLE (-4325 4375);
FORCEPROP 1 LAST VOLTAGE 0.0V
J 0
(-4445 4382);
DISPLAY 0.340426 (-4445 4382);
PAINT SKYBLUE (-4445 4382);
DISPLAY INVISIBLE (-4445 4382);
FORCEPROP 2 LAST CDS_LIB mstr_symbols
J 0
(-4400 4425);
PAINT ORANGE (-4400 4425);
DISPLAY INVISIBLE (-4400 4425);
FORCEADD P3V3_STBY..1
(-4400 4900);
FORCEPROP 3 LASTPIN (-4400 4850) SIG_NAME P3V3_STBY\g
J 0
(-4390 4860);
DISPLAY 0.659574 (-4390 4860);
PAINT MONO (-4390 4860);
DISPLAY INVISIBLE (-4390 4860);
FORCEPROP 1 LAST HDL_POWER P3V3_STBY
J 0
(-4700 4775);
DISPLAY 0.872340 (-4700 4775);
PAINT ORANGE (-4700 4775);
DISPLAY INVISIBLE (-4700 4775);
FORCEPROP 1 LAST BODY_TYPE PLUMBING
J 0
(-4445 4857);
DISPLAY 0.340426 (-4445 4857);
PAINT GREEN (-4445 4857);
DISPLAY INVISIBLE (-4445 4857);
FORCEPROP 1 LAST SIZE 1B
J 0
(-4355 4922);
DISPLAY 0.340426 (-4355 4922);
PAINT GREEN (-4355 4922);
DISPLAY INVISIBLE (-4355 4922);
FORCEPROP 2 LAST CDS_LIB mstr_symbols
J 0
(-4400 4900);
PAINT ORANGE (-4400 4900);
DISPLAY INVISIBLE (-4400 4900);
FORCEPROP 1 LAST PATH I43
J 0
(-4355 4902);
DISPLAY 0.340426 (-4355 4902);
PAINT GREEN (-4355 4902);
DISPLAY INVISIBLE (-4355 4902);
FORCEPROP 1 LAST VOLTAGE 3.3V
J 0
(-4445 4857);
DISPLAY 0.340426 (-4445 4857);
PAINT SKYBLUE (-4445 4857);
DISPLAY INVISIBLE (-4445 4857);
FORCEADD P3V3_STBY..1
(-4500 3650);
FORCEPROP 3 LASTPIN (-4500 3600) SIG_NAME P3V3_STBY\g
J 0
(-4490 3610);
DISPLAY 0.659574 (-4490 3610);
PAINT MONO (-4490 3610);
DISPLAY INVISIBLE (-4490 3610);
FORCEPROP 1 LAST HDL_POWER P3V3_STBY
J 0
(-4800 3525);
DISPLAY 0.872340 (-4800 3525);
PAINT ORANGE (-4800 3525);
DISPLAY INVISIBLE (-4800 3525);
FORCEPROP 1 LAST BODY_TYPE PLUMBING
J 0
(-4545 3607);
DISPLAY 0.340426 (-4545 3607);
PAINT GREEN (-4545 3607);
DISPLAY INVISIBLE (-4545 3607);
FORCEPROP 2 LAST CDS_LIB mstr_symbols
J 0
(-4500 3650);
PAINT ORANGE (-4500 3650);
DISPLAY INVISIBLE (-4500 3650);
FORCEPROP 1 LAST VOLTAGE 3.3V
J 0
(-4545 3607);
DISPLAY 0.340426 (-4545 3607);
PAINT SKYBLUE (-4545 3607);
DISPLAY INVISIBLE (-4545 3607);
FORCEPROP 1 LAST SIZE 1B
J 0
(-4455 3672);
DISPLAY 0.340426 (-4455 3672);
PAINT GREEN (-4455 3672);
DISPLAY INVISIBLE (-4455 3672);
FORCEPROP 1 LAST PATH I44
J 0
(-4455 3652);
DISPLAY 0.340426 (-4455 3652);
PAINT GREEN (-4455 3652);
DISPLAY INVISIBLE (-4455 3652);
FORCEADD RES..1
(-4000 1550);
FORCEPROP 1 LAST PACK_TYPE 0402
J 0
(-3900 1450);
DISPLAY 0.617021 (-3900 1450);
PAINT SKYBLUE (-3900 1450);
FORCEPROP 1 LAST TOLERANCE 1.0%
J 0
(-4000 1450);
DISPLAY 0.617021 (-4000 1450);
PAINT SKYBLUE (-4000 1450);
FORCEPROP 1 LAST VALUE 221
J 2
(-4025 1450);
DISPLAY 0.617021 (-4025 1450);
PAINT SKYBLUE (-4025 1450);
FORCEPROP 1 LAST WATTAGE 1/16W
J 2
(-4025 1400);
DISPLAY 0.617021 (-4025 1400);
PAINT SKYBLUE (-4025 1400);
FORCEPROP 1 LAST LOCATION R1L33
J 0
(-4050 1600);
DISPLAY 0.617021 (-4050 1600);
PAINT AQUA (-4050 1600);
FORCEPROP 1 LAST PART_NUMBER G21796-271
J 0
(-4050 1650);
DISPLAY 0.617021 (-4050 1650);
PAINT BLUE (-4050 1650);
FORCEPROP 1 LASTPIN (-3900 1550) $PN 2
J 0
(-3938 1562);
DISPLAY 0.617021 (-3938 1562);
PAINT ORANGE (-3938 1562);
FORCEPROP 1 LAST MATERIAL CHIP
J 0
(-4000 1400);
DISPLAY 0.617021 (-4000 1400);
PAINT SKYBLUE (-4000 1400);
FORCEPROP 1 LASTPIN (-4100 1550) $PN 1
J 0
(-4088 1562);
DISPLAY 0.617021 (-4088 1562);
PAINT ORANGE (-4088 1562);
FORCEPROP 2 LAST SEC_TYPE 0402
J 0
(-4050 1750);
DISPLAY 1.021277 (-4050 1750);
PAINT ORANGE (-4050 1750);
DISPLAY INVISIBLE (-4050 1750);
FORCEPROP 2 LAST BOM_COST MIO_CHASSIS
J 0
(-4050 1750);
DISPLAY 1.021277 (-4050 1750);
PAINT ORANGE (-4050 1750);
DISPLAY INVISIBLE (-4050 1750);
FORCEPROP 2 LAST CDS_LIB mstr_discrete
J 0
(-4000 1550);
PAINT ORANGE (-4000 1550);
DISPLAY INVISIBLE (-4000 1550);
FORCEPROP 2 LAST ROOM MIO_CHASSIS
J 0
(-4050 1700);
DISPLAY 1.021277 (-4050 1700);
PAINT ORANGE (-4050 1700);
DISPLAY INVISIBLE (-4050 1700);
FORCEPROP 0 LAST SEC 1
J 0
(-4050 1700);
DISPLAY 0.680851 (-4050 1700);
PAINT MONO (-4050 1700);
DISPLAY INVISIBLE (-4050 1700);
FORCEPROP 2 LAST CDS_LOCATION R1L33
J 0
(-4050 1600);
DISPLAY 0.617021 (-4050 1600);
PAINT AQUA (-4050 1600);
DISPLAY INVISIBLE (-4050 1600);
FORCEPROP 1 LAST PATH I45
J 0
(-4050 1700);
DISPLAY 0.978723 (-4050 1700);
PAINT WHITE (-4050 1700);
DISPLAY INVISIBLE (-4050 1700);
FORCEADD FET_N..8
(-5025 1175);
FORCEPROP 1 LAST LOCATION Q9A3
J 0
(-4825 1175);
DISPLAY 0.617021 (-4825 1175);
PAINT AQUA (-4825 1175);
FORCEPROP 1 LASTPIN (-5025 1375) $PN 3
J 2
(-4972 1340);
DISPLAY 0.617021 (-4972 1340);
PAINT WHITE (-4972 1340);
FORCEPROP 1 LAST MATERIAL FET
J 0
(-4825 1075);
DISPLAY 0.617021 (-4825 1075);
PAINT SKYBLUE (-4825 1075);
FORCEPROP 1 LASTPIN (-5025 975) $PN 2
J 2
(-4967 975);
DISPLAY 0.617021 (-4967 975);
PAINT WHITE (-4967 975);
FORCEPROP 1 LASTPIN (-5225 1075) $PN 1
J 2
(-5222 1090);
DISPLAY 0.617021 (-5222 1090);
PAINT WHITE (-5222 1090);
FORCEPROP 1 LAST VALUE 2N7002
J 0
(-4825 1125);
DISPLAY 0.617021 (-4825 1125);
PAINT SKYBLUE (-4825 1125);
FORCEPROP 1 LAST PART_NUMBER C79254-001
J 0
(-4825 975);
DISPLAY 0.617021 (-4825 975);
PAINT BLUE (-4825 975);
FORCEPROP 1 LAST PACK_TYPE SOT23LF
J 0
(-4825 1025);
DISPLAY 0.978723 (-4825 1025);
PAINT SKYBLUE (-4825 1025);
DISPLAY INVISIBLE (-4825 1025);
FORCEPROP 2 LAST SEC_TYPE SOT23LF
J 0
(-4825 1275);
DISPLAY 1.021277 (-4825 1275);
PAINT ORANGE (-4825 1275);
DISPLAY INVISIBLE (-4825 1275);
FORCEPROP 2 LAST BOM_COST MIO_CHASSIS
J 0
(-4825 1275);
DISPLAY 1.021277 (-4825 1275);
PAINT ORANGE (-4825 1275);
DISPLAY INVISIBLE (-4825 1275);
FORCEPROP 2 LAST SEC 1
J 0
(-4825 1275);
DISPLAY 0.680851 (-4825 1275);
PAINT MONO (-4825 1275);
DISPLAY INVISIBLE (-4825 1275);
FORCEPROP 2 LAST CDS_LOCATION Q9A3
J 0
(-4825 1175);
DISPLAY 0.617021 (-4825 1175);
PAINT AQUA (-4825 1175);
DISPLAY INVISIBLE (-4825 1175);
FORCEPROP 1 LAST PATH I49
J 0
(-4825 1225);
DISPLAY 0.978723 (-4825 1225);
PAINT BLUE (-4825 1225);
DISPLAY INVISIBLE (-4825 1225);
FORCEPROP 2 LAST ROOM MIO_CHASSIS
J 0
(-4825 1225);
DISPLAY 1.021277 (-4825 1225);
PAINT ORANGE (-4825 1225);
DISPLAY INVISIBLE (-4825 1225);
FORCEPROP 2 LAST CDS_LIB mstr_discrete
J 0
(-5025 1175);
PAINT ORANGE (-5025 1175);
DISPLAY INVISIBLE (-5025 1175);
FORCEADD RES..2
(-5925 4475);
FORCEPROP 1 LAST PART_NUMBER G21796-072
J 0
(-5885 4350);
DISPLAY 0.617021 (-5885 4350);
PAINT BLUE (-5885 4350);
FORCEPROP 1 LAST WATTAGE 1/16W
J 0
(-5885 4450);
DISPLAY 0.617021 (-5885 4450);
PAINT SKYBLUE (-5885 4450);
FORCEPROP 1 LAST MATERIAL CHIP
J 0
(-5885 4400);
DISPLAY 0.617021 (-5885 4400);
PAINT SKYBLUE (-5885 4400);
FORCEPROP 1 LAST TOLERANCE 1%
J 0
(-5880 4500);
DISPLAY 0.617021 (-5880 4500);
PAINT SKYBLUE (-5880 4500);
FORCEPROP 1 LAST VALUE 4.75K
J 0
(-5880 4550);
DISPLAY 0.617021 (-5880 4550);
PAINT SKYBLUE (-5880 4550);
FORCEPROP 1 LASTPIN (-5925 4575) $PN 1
J 0
(-5920 4537);
DISPLAY 0.617021 (-5920 4537);
PAINT ORANGE (-5920 4537);
FORCEPROP 1 LASTPIN (-5925 4375) $PN 2
J 0
(-5920 4385);
DISPLAY 0.617021 (-5920 4385);
PAINT ORANGE (-5920 4385);
FORCEPROP 1 LAST LOCATION R1L27
J 0
(-5880 4600);
DISPLAY 0.617021 (-5880 4600);
PAINT AQUA (-5880 4600);
FORCEPROP 1 LAST PACK_TYPE 0402
J 0
(-5885 4300);
DISPLAY 0.617021 (-5885 4300);
PAINT SKYBLUE (-5885 4300);
FORCEPROP 2 LAST ROOM MIO_CHASSIS
J 0
(-5875 4650);
DISPLAY 1.021277 (-5875 4650);
PAINT ORANGE (-5875 4650);
DISPLAY INVISIBLE (-5875 4650);
FORCEPROP 1 LAST PATH I5
J 0
(-5875 4650);
DISPLAY 0.978723 (-5875 4650);
PAINT WHITE (-5875 4650);
DISPLAY INVISIBLE (-5875 4650);
FORCEPROP 0 LAST SEC 1
J 0
(-5875 4650);
DISPLAY 0.680851 (-5875 4650);
PAINT MONO (-5875 4650);
DISPLAY INVISIBLE (-5875 4650);
FORCEPROP 2 LAST SEC_TYPE 0402
J 0
(-5875 4700);
DISPLAY 1.021277 (-5875 4700);
PAINT ORANGE (-5875 4700);
DISPLAY INVISIBLE (-5875 4700);
FORCEPROP 2 LAST BOM_COST MIO_CHASSIS
J 0
(-5875 4700);
DISPLAY 1.021277 (-5875 4700);
PAINT ORANGE (-5875 4700);
DISPLAY INVISIBLE (-5875 4700);
FORCEPROP 2 LAST CDS_LOCATION R1L27
J 0
(-5880 4600);
DISPLAY 0.617021 (-5880 4600);
PAINT AQUA (-5880 4600);
DISPLAY INVISIBLE (-5880 4600);
FORCEPROP 2 LAST CDS_LIB mstr_discrete
J 0
(-5925 4475);
PAINT ORANGE (-5925 4475);
DISPLAY INVISIBLE (-5925 4475);
FORCEADD LED..3
(-1700 1025);
FORCEPROP 1 LAST PART_NUMBER C96565-012
J 0
(-1800 875);
DISPLAY 0.617021 (-1800 875);
PAINT BLUE (-1800 875);
FORCEPROP 2 LASTPIN (-1600 1025) $PN 2
J 0
(-1590 1035);
DISPLAY 0.617021 (-1590 1035);
PAINT MONO (-1590 1035);
FORCEPROP 2 LASTPIN (-1800 1025) $PN 1
J 2
(-1810 1035);
DISPLAY 0.617021 (-1810 1035);
PAINT MONO (-1810 1035);
FORCEPROP 1 LAST LOCATION DS9A1
J 0
(-1800 1225);
DISPLAY 0.617021 (-1800 1225);
PAINT AQUA (-1800 1225);
FORCEPROP 1 LAST MATERIAL IC
J 0
(-1800 1175);
DISPLAY 0.617021 (-1800 1175);
PAINT SKYBLUE (-1800 1175);
FORCEPROP 1 LAST COLOR BLUE
J 0
(-1800 1125);
DISPLAY 0.617021 (-1800 1125);
PAINT BLUE (-1800 1125);
FORCEPROP 1 LAST PATH I50
J 0
(-1350 1175);
DISPLAY 0.978723 (-1350 1175);
PAINT BLUE (-1350 1175);
DISPLAY INVISIBLE (-1350 1175);
FORCEPROP 2 LAST CDS_LIB mstr_discrete
J 0
(-1700 1025);
PAINT MONO (-1700 1025);
DISPLAY INVISIBLE (-1700 1025);
FORCEPROP 1 LAST PACK_TYPE 1NC
J 0
(-1800 1275);
DISPLAY 0.978723 (-1800 1275);
PAINT SKYBLUE (-1800 1275);
DISPLAY INVISIBLE (-1800 1275);
FORCEPROP 2 LAST BOM_COST MIO_CHASSIS
J 0
(-1800 1325);
DISPLAY 1.021277 (-1800 1325);
PAINT ORANGE (-1800 1325);
DISPLAY INVISIBLE (-1800 1325);
FORCEPROP 2 LAST CDS_SEC 1
J 0
(-1800 1275);
PAINT MONO (-1800 1275);
DISPLAY INVISIBLE (-1800 1275);
FORCEPROP 2 LAST $SEC 1
J 0
(-1800 1275);
PAINT MONO (-1800 1275);
DISPLAY INVISIBLE (-1800 1275);
FORCEPROP 2 LAST CDS_LOCATION DS9A1
J 0
(-1800 1225);
DISPLAY 0.617021 (-1800 1225);
PAINT AQUA (-1800 1225);
DISPLAY INVISIBLE (-1800 1225);
FORCEPROP 2 LAST ROOM MIO_CHASSIS
J 0
(-1800 1275);
DISPLAY 1.021277 (-1800 1275);
PAINT ORANGE (-1800 1275);
DISPLAY INVISIBLE (-1800 1275);
FORCEADD OFFPAGE..1
(-5900 1075);
FORCEPROP 2 LAST $XR1 136 
J 0
(-6272 1075);
DISPLAY 0.638298 (-6272 1075);
PAINT MONO (-6272 1075);
FORCEPROP 2 LAST $XR0 119 
J 0
(-6152 1075);
DISPLAY 0.638298 (-6152 1075);
PAINT MONO (-6152 1075);
FORCEPROP 1 LAST COMMENT_BODY TRUE
J 0
(-5775 975);
DISPLAY 0.872340 (-5775 975);
PAINT GREEN (-5775 975);
DISPLAY INVISIBLE (-5775 975);
FORCEPROP 1 LAST OFFPAGE TRUE
J 0
(-5575 950);
DISPLAY 0.872340 (-5575 950);
PAINT GREEN (-5575 950);
DISPLAY INVISIBLE (-5575 950);
FORCEPROP 2 LAST PATH I52
J 0
(-5850 1150);
DISPLAY 1.021277 (-5850 1150);
PAINT ORANGE (-5850 1150);
DISPLAY INVISIBLE (-5850 1150);
FORCEPROP 2 LAST CDS_LIB mstr_standard
J 0
(-5900 1075);
PAINT ORANGE (-5900 1075);
DISPLAY INVISIBLE (-5900 1075);
FORCEADD GND..1
(-5025 750);
FORCEPROP 3 LASTPIN (-5025 800) SIG_NAME GND\g
J 0
(-5015 810);
DISPLAY 0.659574 (-5015 810);
PAINT MONO (-5015 810);
DISPLAY INVISIBLE (-5015 810);
FORCEPROP 1 LAST HDL_POWER GND
J 0
(-5025 900);
DISPLAY 0.872340 (-5025 900);
PAINT GREEN (-5025 900);
DISPLAY INVISIBLE (-5025 900);
FORCEPROP 1 LAST BODY_TYPE PLUMBING
J 0
(-5070 707);
DISPLAY 0.340426 (-5070 707);
PAINT GREEN (-5070 707);
DISPLAY INVISIBLE (-5070 707);
FORCEPROP 1 LAST PATH I54
J 0
(-4950 750);
DISPLAY 0.872340 (-4950 750);
PAINT AQUA (-4950 750);
DISPLAY INVISIBLE (-4950 750);
FORCEPROP 2 LAST CDS_LIB mstr_symbols
J 0
(-5025 750);
PAINT ORANGE (-5025 750);
DISPLAY INVISIBLE (-5025 750);
FORCEPROP 1 LAST SIZE 1B
J 0
(-4950 700);
DISPLAY 0.872340 (-4950 700);
PAINT AQUA (-4950 700);
DISPLAY INVISIBLE (-4950 700);
FORCEPROP 1 LAST VOLTAGE 0.0V
J 0
(-5070 707);
DISPLAY 0.340426 (-5070 707);
PAINT SKYBLUE (-5070 707);
DISPLAY INVISIBLE (-5070 707);
FORCEADD TTL1G86..1
(-2750 1025);
FORCEPROP 1 LAST VALUE 74AHCT1G86
J 0
(-2900 1175);
DISPLAY 0.617021 (-2900 1175);
PAINT SKYBLUE (-2900 1175);
FORCEPROP 2 LASTPIN (-2450 1025) $PN 4
J 0
(-2440 1035);
DISPLAY 0.617021 (-2440 1035);
PAINT MONO (-2440 1035);
FORCEPROP 1 LAST LOCATION U1L2
J 0
(-2900 1275);
DISPLAY 0.617021 (-2900 1275);
PAINT AQUA (-2900 1275);
FORCEPROP 1 LAST MATERIAL IC
J 0
(-2900 1225);
DISPLAY 0.617021 (-2900 1225);
PAINT SKYBLUE (-2900 1225);
FORCEPROP 2 LASTPIN (-2950 1075) $PN 1
J 2
(-2960 1085);
DISPLAY 0.617021 (-2960 1085);
PAINT MONO (-2960 1085);
FORCEPROP 1 LAST POWER_GROUP VCC=P5V_STBY;GND=GND;
J 0
(-2900 775);
DISPLAY 0.617021 (-2900 775);
PAINT ORANGE (-2900 775);
FORCEPROP 1 LAST PART_NUMBER D39848-001
J 0
(-2900 825);
DISPLAY 0.617021 (-2900 825);
PAINT BLUE (-2900 825);
FORCEPROP 2 LASTPIN (-2950 975) $PN 2
J 2
(-2960 985);
DISPLAY 0.617021 (-2960 985);
PAINT MONO (-2960 985);
FORCEPROP 1 LAST PATH I57
J 0
(-2675 1225);
PAINT GREEN (-2675 1225);
DISPLAY INVISIBLE (-2675 1225);
FORCEPROP 2 LAST CDS_LIB mstr_ttl
J 0
(-2750 1025);
PAINT ORANGE (-2750 1025);
DISPLAY INVISIBLE (-2750 1025);
FORCEPROP 2 LAST ROOM MIO_CHASSIS
J 0
(-2900 1325);
DISPLAY 1.021277 (-2900 1325);
PAINT ORANGE (-2900 1325);
DISPLAY INVISIBLE (-2900 1325);
FORCEPROP 2 LAST $SEC 1
J 0
(-2900 1325);
PAINT MONO (-2900 1325);
DISPLAY INVISIBLE (-2900 1325);
FORCEPROP 2 LAST CDS_SEC 1
J 0
(-2900 1325);
PAINT MONO (-2900 1325);
DISPLAY INVISIBLE (-2900 1325);
FORCEPROP 2 LAST BOM_COST MIO_CHASSIS
J 0
(-2900 1375);
DISPLAY 1.021277 (-2900 1375);
PAINT ORANGE (-2900 1375);
DISPLAY INVISIBLE (-2900 1375);
FORCEPROP 1 LAST PACK_TYPE SOTLF
J 0
(-2900 1325);
PAINT SKYBLUE (-2900 1325);
DISPLAY INVISIBLE (-2900 1325);
FORCEPROP 2 LAST CDS_LOCATION U1L2
J 0
(-2900 1275);
DISPLAY 0.617021 (-2900 1275);
PAINT AQUA (-2900 1275);
DISPLAY INVISIBLE (-2900 1275);
FORCEADD RES..2
(-1175 1350);
FORCEPROP 1 LAST PART_NUMBER G21497-024
J 0
(-1135 1225);
DISPLAY 0.617021 (-1135 1225);
PAINT BLUE (-1135 1225);
FORCEPROP 1 LASTPIN (-1175 1250) $PN 2
J 0
(-1170 1260);
DISPLAY 0.617021 (-1170 1260);
PAINT ORANGE (-1170 1260);
FORCEPROP 1 LASTPIN (-1175 1450) $PN 1
J 0
(-1170 1412);
DISPLAY 0.617021 (-1170 1412);
PAINT ORANGE (-1170 1412);
FORCEPROP 1 LAST MATERIAL CHIP
J 0
(-1135 1275);
DISPLAY 0.617021 (-1135 1275);
PAINT SKYBLUE (-1135 1275);
FORCEPROP 1 LAST WATTAGE 1/16W
J 0
(-1135 1325);
DISPLAY 0.617021 (-1135 1325);
PAINT SKYBLUE (-1135 1325);
FORCEPROP 1 LAST TOLERANCE 5%
J 0
(-1130 1375);
DISPLAY 0.617021 (-1130 1375);
PAINT SKYBLUE (-1130 1375);
FORCEPROP 1 LAST VALUE 470.0
J 0
(-1130 1425);
DISPLAY 0.617021 (-1130 1425);
PAINT SKYBLUE (-1130 1425);
FORCEPROP 1 LAST PACK_TYPE 0402
J 0
(-1135 1175);
DISPLAY 0.617021 (-1135 1175);
PAINT SKYBLUE (-1135 1175);
FORCEPROP 1 LAST LOCATION R1L8
J 0
(-1130 1475);
DISPLAY 0.617021 (-1130 1475);
PAINT AQUA (-1130 1475);
FORCEPROP 2 LAST SEC_TYPE 0402
J 0
(-1125 1575);
DISPLAY 1.021277 (-1125 1575);
PAINT ORANGE (-1125 1575);
DISPLAY INVISIBLE (-1125 1575);
FORCEPROP 2 LAST BOM_COST MIO_CHASSIS
J 0
(-1125 1575);
DISPLAY 1.021277 (-1125 1575);
PAINT ORANGE (-1125 1575);
DISPLAY INVISIBLE (-1125 1575);
FORCEPROP 0 LAST SEC 1
J 0
(-1125 1525);
DISPLAY 0.680851 (-1125 1525);
PAINT MONO (-1125 1525);
DISPLAY INVISIBLE (-1125 1525);
FORCEPROP 1 LAST PATH I58
J 0
(-1125 1525);
DISPLAY 0.978723 (-1125 1525);
PAINT WHITE (-1125 1525);
DISPLAY INVISIBLE (-1125 1525);
FORCEPROP 2 LAST ROOM MIO_CHASSIS
J 0
(-1125 1525);
DISPLAY 1.021277 (-1125 1525);
PAINT ORANGE (-1125 1525);
DISPLAY INVISIBLE (-1125 1525);
FORCEPROP 2 LAST CDS_LIB mstr_discrete
J 0
(-1175 1350);
PAINT ORANGE (-1175 1350);
DISPLAY INVISIBLE (-1175 1350);
FORCEPROP 2 LAST CDS_LOCATION R1L8
J 0
(-1130 1475);
DISPLAY 0.617021 (-1130 1475);
PAINT AQUA (-1130 1475);
DISPLAY INVISIBLE (-1130 1475);
FORCEADD P5V_STBY..1
(-1175 1700);
FORCEPROP 3 LASTPIN (-1175 1650) SIG_NAME P5V_STBY\g
J 0
(-1165 1660);
DISPLAY 0.659574 (-1165 1660);
PAINT MONO (-1165 1660);
DISPLAY INVISIBLE (-1165 1660);
FORCEPROP 1 LAST HDL_POWER P5V_STBY
J 0
(-1475 1575);
DISPLAY 0.872340 (-1475 1575);
PAINT ORANGE (-1475 1575);
DISPLAY INVISIBLE (-1475 1575);
FORCEPROP 1 LAST BODY_TYPE PLUMBING
J 0
(-1220 1657);
DISPLAY 0.340426 (-1220 1657);
PAINT GREEN (-1220 1657);
DISPLAY INVISIBLE (-1220 1657);
FORCEPROP 1 LAST VOLTAGE 5.0V
J 0
(-1220 1657);
DISPLAY 0.340426 (-1220 1657);
PAINT SKYBLUE (-1220 1657);
DISPLAY INVISIBLE (-1220 1657);
FORCEPROP 2 LAST CDS_LIB mstr_symbols
J 0
(-1175 1700);
PAINT ORANGE (-1175 1700);
DISPLAY INVISIBLE (-1175 1700);
FORCEPROP 1 LAST SIZE 1B
J 0
(-1130 1722);
DISPLAY 0.340426 (-1130 1722);
PAINT GREEN (-1130 1722);
DISPLAY INVISIBLE (-1130 1722);
FORCEPROP 1 LAST PATH I59
J 0
(-1130 1702);
DISPLAY 0.340426 (-1130 1702);
PAINT GREEN (-1130 1702);
DISPLAY INVISIBLE (-1130 1702);
FORCEADD P3V3_STBY..1
(-5925 4800);
FORCEPROP 3 LASTPIN (-5925 4750) SIG_NAME P3V3_STBY\g
J 0
(-5915 4760);
DISPLAY 0.659574 (-5915 4760);
PAINT MONO (-5915 4760);
DISPLAY INVISIBLE (-5915 4760);
FORCEPROP 1 LAST HDL_POWER P3V3_STBY
J 0
(-6225 4675);
DISPLAY 0.872340 (-6225 4675);
PAINT ORANGE (-6225 4675);
DISPLAY INVISIBLE (-6225 4675);
FORCEPROP 1 LAST BODY_TYPE PLUMBING
J 0
(-5970 4757);
DISPLAY 0.340426 (-5970 4757);
PAINT GREEN (-5970 4757);
DISPLAY INVISIBLE (-5970 4757);
FORCEPROP 1 LAST PATH I6
J 0
(-5880 4802);
DISPLAY 0.340426 (-5880 4802);
PAINT GREEN (-5880 4802);
DISPLAY INVISIBLE (-5880 4802);
FORCEPROP 1 LAST SIZE 1B
J 0
(-5880 4822);
DISPLAY 0.340426 (-5880 4822);
PAINT GREEN (-5880 4822);
DISPLAY INVISIBLE (-5880 4822);
FORCEPROP 2 LAST CDS_LIB mstr_symbols
J 0
(-5925 4800);
PAINT ORANGE (-5925 4800);
DISPLAY INVISIBLE (-5925 4800);
FORCEPROP 1 LAST VOLTAGE 3.3V
J 0
(-5970 4757);
DISPLAY 0.340426 (-5970 4757);
PAINT SKYBLUE (-5970 4757);
DISPLAY INVISIBLE (-5970 4757);
FORCEADD OFFPAGE..1
(-4075 975);
FORCEPROP 2 LAST $XR1 133 
J 0
(-4447 975);
DISPLAY 0.638298 (-4447 975);
PAINT MONO (-4447 975);
FORCEPROP 2 LAST $XR0 120 
J 0
(-4327 975);
DISPLAY 0.638298 (-4327 975);
PAINT MONO (-4327 975);
FORCEPROP 2 LAST $XR2 146 
J 0
(-4327 939);
DISPLAY 0.638298 (-4327 939);
PAINT MONO (-4327 939);
FORCEPROP 2 LAST $XR3 151 
J 0
(-4327 939);
DISPLAY 0.638298 (-4327 939);
PAINT MONO (-4327 939);
FORCEPROP 1 LAST COMMENT_BODY TRUE
J 0
(-3950 875);
DISPLAY 0.872340 (-3950 875);
PAINT GREEN (-3950 875);
DISPLAY INVISIBLE (-3950 875);
FORCEPROP 1 LAST OFFPAGE TRUE
J 0
(-3750 850);
DISPLAY 0.872340 (-3750 850);
PAINT GREEN (-3750 850);
DISPLAY INVISIBLE (-3750 850);
FORCEPROP 2 LAST PATH I61
J 0
(-4025 1050);
DISPLAY 1.021277 (-4025 1050);
PAINT ORANGE (-4025 1050);
DISPLAY INVISIBLE (-4025 1050);
FORCEPROP 2 LAST CDS_LIB mstr_standard
J 0
(-4075 975);
PAINT ORANGE (-4075 975);
DISPLAY INVISIBLE (-4075 975);
FORCEADD OFFPAGE..1
(-4075 1075);
FORCEPROP 2 LAST $XR1 190 
J 0
(-4447 1075);
DISPLAY 0.638298 (-4447 1075);
PAINT MONO (-4447 1075);
FORCEPROP 2 LAST $XR0 196 
J 0
(-4327 1075);
DISPLAY 0.638298 (-4327 1075);
PAINT MONO (-4327 1075);
FORCEPROP 1 LAST COMMENT_BODY TRUE
J 0
(-3950 975);
DISPLAY 0.872340 (-3950 975);
PAINT GREEN (-3950 975);
DISPLAY INVISIBLE (-3950 975);
FORCEPROP 1 LAST OFFPAGE TRUE
J 0
(-3750 950);
DISPLAY 0.872340 (-3750 950);
PAINT GREEN (-3750 950);
DISPLAY INVISIBLE (-3750 950);
FORCEPROP 2 LAST PATH I62
J 0
(-4025 1150);
DISPLAY 1.021277 (-4025 1150);
PAINT ORANGE (-4025 1150);
DISPLAY INVISIBLE (-4025 1150);
FORCEPROP 2 LAST CDS_LIB mstr_standard
J 0
(-4075 1075);
PAINT ORANGE (-4075 1075);
DISPLAY INVISIBLE (-4075 1075);
FORCEADD RES..1
(-3525 1075);
FORCEPROP 1 LAST WATTAGE 1/16W
J 2
(-3550 925);
DISPLAY 0.617021 (-3550 925);
PAINT SKYBLUE (-3550 925);
FORCEPROP 1 LAST VALUE 0.0
J 2
(-3550 975);
DISPLAY 0.617021 (-3550 975);
PAINT SKYBLUE (-3550 975);
FORCEPROP 1 LAST PART_NUMBER G21497-005
J 0
(-3575 1175);
DISPLAY 0.617021 (-3575 1175);
PAINT BLUE (-3575 1175);
FORCEPROP 1 LAST LOCATION R1L12
J 0
(-3575 1125);
DISPLAY 0.617021 (-3575 1125);
PAINT AQUA (-3575 1125);
FORCEPROP 1 LAST TOLERANCE 5%
J 0
(-3525 975);
DISPLAY 0.617021 (-3525 975);
PAINT SKYBLUE (-3525 975);
FORCEPROP 1 LAST MATERIAL CHIP
J 0
(-3525 925);
DISPLAY 0.617021 (-3525 925);
PAINT SKYBLUE (-3525 925);
FORCEPROP 1 LAST PACK_TYPE 0402
J 0
(-3275 925);
DISPLAY 0.617021 (-3275 925);
PAINT SKYBLUE (-3275 925);
FORCEPROP 1 LASTPIN (-3625 1075) $PN 1
J 0
(-3613 1087);
DISPLAY 0.617021 (-3613 1087);
PAINT ORANGE (-3613 1087);
FORCEPROP 1 LASTPIN (-3425 1075) $PN 2
J 0
(-3463 1087);
DISPLAY 0.617021 (-3463 1087);
PAINT ORANGE (-3463 1087);
FORCEPROP 2 LAST BOM_COST MIO_CHASSIS
J 0
(-3575 1275);
DISPLAY 1.021277 (-3575 1275);
PAINT ORANGE (-3575 1275);
DISPLAY INVISIBLE (-3575 1275);
FORCEPROP 2 LAST ROOM MIO_CHASSIS
J 0
(-3575 1225);
DISPLAY 1.021277 (-3575 1225);
PAINT ORANGE (-3575 1225);
DISPLAY INVISIBLE (-3575 1225);
FORCEPROP 1 LAST PATH I63
J 0
(-3575 1225);
DISPLAY 0.978723 (-3575 1225);
PAINT WHITE (-3575 1225);
DISPLAY INVISIBLE (-3575 1225);
FORCEPROP 2 LAST SEC 1
J 0
(-3575 1275);
PAINT MONO (-3575 1275);
DISPLAY INVISIBLE (-3575 1275);
FORCEPROP 2 LAST SEC_TYPE 0402
J 0
(-3575 1275);
DISPLAY 1.021277 (-3575 1275);
PAINT ORANGE (-3575 1275);
DISPLAY INVISIBLE (-3575 1275);
FORCEPROP 2 LAST CDS_LIB mstr_discrete
J 0
(-3525 1075);
PAINT ORANGE (-3525 1075);
DISPLAY INVISIBLE (-3525 1075);
FORCEPROP 2 LAST CDS_LOCATION R1L12
J 0
(-3575 1125);
DISPLAY 0.617021 (-3575 1125);
PAINT AQUA (-3575 1125);
DISPLAY INVISIBLE (-3575 1125);
FORCEADD CAP_A..1
(-2900 1725);
FORCEPROP 1 LAST TOLERANCE 10%
J 0
(-2850 1675);
DISPLAY 0.617021 (-2850 1675);
PAINT SKYBLUE (-2850 1675);
FORCEPROP 1 LAST PART_NUMBER A36096-030
J 0
(-2850 1575);
DISPLAY 0.617021 (-2850 1575);
PAINT BLUE (-2850 1575);
FORCEPROP 1 LAST VALUE 0.1UF
J 0
(-2850 1775);
DISPLAY 0.617021 (-2850 1775);
PAINT SKYBLUE (-2850 1775);
FORCEPROP 1 LASTPIN (-2900 1625) $PN 2
J 0
(-2890 1605);
DISPLAY 0.617021 (-2890 1605);
PAINT ORANGE (-2890 1605);
FORCEPROP 1 LAST MATERIAL X7R
J 0
(-2850 1625);
DISPLAY 0.617021 (-2850 1625);
PAINT SKYBLUE (-2850 1625);
FORCEPROP 1 LAST PACK_TYPE 0402V
J 0
(-2850 1525);
DISPLAY 0.617021 (-2850 1525);
PAINT SKYBLUE (-2850 1525);
FORCEPROP 1 LAST VOLTAGE 16V
J 0
(-2850 1725);
DISPLAY 0.617021 (-2850 1725);
PAINT SKYBLUE (-2850 1725);
FORCEPROP 1 LASTPIN (-2900 1825) $PN 1
J 0
(-2890 1805);
DISPLAY 0.617021 (-2890 1805);
PAINT ORANGE (-2890 1805);
FORCEPROP 1 LAST LOCATION C1L4
J 0
(-2850 1825);
DISPLAY 0.617021 (-2850 1825);
PAINT AQUA (-2850 1825);
FORCEPROP 2 LAST SEC_TYPE 0402V
J 0
(-2850 1925);
DISPLAY 1.021277 (-2850 1925);
PAINT ORANGE (-2850 1925);
DISPLAY INVISIBLE (-2850 1925);
FORCEPROP 2 LAST BOM_COST MIO_CHASSIS
J 0
(-2850 1925);
DISPLAY 1.021277 (-2850 1925);
PAINT ORANGE (-2850 1925);
DISPLAY INVISIBLE (-2850 1925);
FORCEPROP 2 LAST CDS_LOCATION C1L4
J 0
(-2850 1825);
DISPLAY 0.617021 (-2850 1825);
PAINT AQUA (-2850 1825);
DISPLAY INVISIBLE (-2850 1825);
FORCEPROP 2 LAST SEC 1
J 0
(-2850 1875);
DISPLAY 0.680851 (-2850 1875);
PAINT MONO (-2850 1875);
DISPLAY INVISIBLE (-2850 1875);
FORCEPROP 2 LAST ROOM MIO_CHASSIS
J 0
(-2850 1875);
DISPLAY 1.021277 (-2850 1875);
PAINT ORANGE (-2850 1875);
DISPLAY INVISIBLE (-2850 1875);
FORCEPROP 1 LAST PATH I64
J 0
(-2850 1875);
DISPLAY 0.978723 (-2850 1875);
PAINT WHITE (-2850 1875);
DISPLAY INVISIBLE (-2850 1875);
FORCEPROP 2 LAST CDS_SEC 1
J 0
(-2850 1875);
PAINT ORANGE (-2850 1875);
DISPLAY INVISIBLE (-2850 1875);
FORCEPROP 2 LAST CDS_LIB dev_discrete
J 0
(-2900 1725);
PAINT ORANGE (-2900 1725);
DISPLAY INVISIBLE (-2900 1725);
FORCEADD GND..1
(-2900 1475);
FORCEPROP 3 LASTPIN (-2900 1525) SIG_NAME GND\g
J 0
(-2890 1535);
DISPLAY 0.659574 (-2890 1535);
PAINT MONO (-2890 1535);
DISPLAY INVISIBLE (-2890 1535);
FORCEPROP 1 LAST HDL_POWER GND
J 0
(-2900 1625);
DISPLAY 0.872340 (-2900 1625);
PAINT GREEN (-2900 1625);
DISPLAY INVISIBLE (-2900 1625);
FORCEPROP 1 LAST BODY_TYPE PLUMBING
J 0
(-2945 1432);
DISPLAY 0.340426 (-2945 1432);
PAINT GREEN (-2945 1432);
DISPLAY INVISIBLE (-2945 1432);
FORCEPROP 1 LAST PATH I66
J 0
(-2825 1475);
DISPLAY 0.872340 (-2825 1475);
PAINT AQUA (-2825 1475);
DISPLAY INVISIBLE (-2825 1475);
FORCEPROP 1 LAST SIZE 1B
J 0
(-2825 1425);
DISPLAY 0.872340 (-2825 1425);
PAINT AQUA (-2825 1425);
DISPLAY INVISIBLE (-2825 1425);
FORCEPROP 2 LAST CDS_LIB mstr_symbols
J 0
(-2900 1475);
PAINT ORANGE (-2900 1475);
DISPLAY INVISIBLE (-2900 1475);
FORCEPROP 1 LAST VOLTAGE 0.0V
J 0
(-2945 1432);
DISPLAY 0.340426 (-2945 1432);
PAINT SKYBLUE (-2945 1432);
DISPLAY INVISIBLE (-2945 1432);
FORCEADD LED..3
(-4600 1550);
FORCEPROP 1 LAST PART_NUMBER C96565-003
J 0
(-4700 1400);
DISPLAY 0.617021 (-4700 1400);
PAINT BLUE (-4700 1400);
FORCEPROP 1 LAST COLOR YELLOW
J 0
(-4700 1650);
DISPLAY 0.617021 (-4700 1650);
PAINT BLUE (-4700 1650);
FORCEPROP 1 LAST LOCATION DS9A3
J 0
(-4700 1750);
DISPLAY 0.617021 (-4700 1750);
PAINT AQUA (-4700 1750);
FORCEPROP 2 LASTPIN (-4700 1550) $PN 1
J 2
(-4710 1560);
DISPLAY 0.617021 (-4710 1560);
PAINT ORANGE (-4710 1560);
FORCEPROP 1 LAST MATERIAL IC
J 0
(-4700 1700);
DISPLAY 0.617021 (-4700 1700);
PAINT SKYBLUE (-4700 1700);
FORCEPROP 2 LASTPIN (-4500 1550) $PN 2
J 0
(-4490 1560);
DISPLAY 0.617021 (-4490 1560);
PAINT ORANGE (-4490 1560);
FORCEPROP 2 LAST CDS_LIB mstr_discrete
J 0
(-4600 1550);
PAINT MONO (-4600 1550);
DISPLAY INVISIBLE (-4600 1550);
FORCEPROP 1 LAST PATH I67
J 0
(-4250 1700);
DISPLAY 0.978723 (-4250 1700);
PAINT BLUE (-4250 1700);
DISPLAY INVISIBLE (-4250 1700);
FORCEPROP 1 LAST PACK_TYPE 1NCLF
J 0
(-4700 1800);
DISPLAY 0.978723 (-4700 1800);
PAINT SKYBLUE (-4700 1800);
DISPLAY INVISIBLE (-4700 1800);
FORCEPROP 2 LAST SEC_TYPE 1NCLF
J 0
(-4700 1800);
DISPLAY 1.021277 (-4700 1800);
PAINT ORANGE (-4700 1800);
DISPLAY INVISIBLE (-4700 1800);
FORCEPROP 2 LAST BOM_COST MIO_CHASSIS
J 0
(-4700 1850);
DISPLAY 1.021277 (-4700 1850);
PAINT ORANGE (-4700 1850);
DISPLAY INVISIBLE (-4700 1850);
FORCEPROP 2 LAST SEC 1
J 0
(-4700 1800);
DISPLAY 0.680851 (-4700 1800);
PAINT MONO (-4700 1800);
DISPLAY INVISIBLE (-4700 1800);
FORCEPROP 2 LAST CDS_LOCATION DS9A3
J 0
(-4700 1750);
DISPLAY 0.617021 (-4700 1750);
PAINT AQUA (-4700 1750);
DISPLAY INVISIBLE (-4700 1750);
FORCEPROP 2 LAST ROOM MIO_CHASSIS
J 0
(-4700 1800);
DISPLAY 1.021277 (-4700 1800);
PAINT ORANGE (-4700 1800);
DISPLAY INVISIBLE (-4700 1800);
FORCEADD P3V3_STBY..1
(-575 3800);
FORCEPROP 3 LASTPIN (-575 3750) SIG_NAME P3V3_STBY\g
J 0
(-565 3760);
DISPLAY 0.659574 (-565 3760);
PAINT MONO (-565 3760);
DISPLAY INVISIBLE (-565 3760);
FORCEPROP 1 LAST HDL_POWER P3V3_STBY
J 0
(-875 3675);
DISPLAY 0.872340 (-875 3675);
PAINT ORANGE (-875 3675);
DISPLAY INVISIBLE (-875 3675);
FORCEPROP 1 LAST BODY_TYPE PLUMBING
J 0
(-620 3757);
DISPLAY 0.340426 (-620 3757);
PAINT GREEN (-620 3757);
DISPLAY INVISIBLE (-620 3757);
FORCEPROP 2 LAST CDS_LIB mstr_symbols
J 0
(-575 3800);
PAINT ORANGE (-575 3800);
DISPLAY INVISIBLE (-575 3800);
FORCEPROP 1 LAST VOLTAGE 3.3V
J 0
(-620 3757);
DISPLAY 0.340426 (-620 3757);
PAINT SKYBLUE (-620 3757);
DISPLAY INVISIBLE (-620 3757);
FORCEPROP 1 LAST SIZE 1B
J 0
(-530 3822);
DISPLAY 0.340426 (-530 3822);
PAINT GREEN (-530 3822);
DISPLAY INVISIBLE (-530 3822);
FORCEPROP 1 LAST PATH I70
J 0
(-530 3802);
DISPLAY 0.340426 (-530 3802);
PAINT GREEN (-530 3802);
DISPLAY INVISIBLE (-530 3802);
FORCEADD GND..1
(-575 3200);
FORCEPROP 3 LASTPIN (-575 3250) SIG_NAME GND\g
J 0
(-565 3260);
DISPLAY 0.659574 (-565 3260);
PAINT MONO (-565 3260);
DISPLAY INVISIBLE (-565 3260);
FORCEPROP 1 LAST HDL_POWER GND
J 0
(-575 3350);
DISPLAY 0.872340 (-575 3350);
PAINT GREEN (-575 3350);
DISPLAY INVISIBLE (-575 3350);
FORCEPROP 1 LAST BODY_TYPE PLUMBING
J 0
(-620 3157);
DISPLAY 0.340426 (-620 3157);
PAINT GREEN (-620 3157);
DISPLAY INVISIBLE (-620 3157);
FORCEPROP 1 LAST SIZE 1B
J 0
(-500 3150);
DISPLAY 0.872340 (-500 3150);
PAINT AQUA (-500 3150);
DISPLAY INVISIBLE (-500 3150);
FORCEPROP 1 LAST PATH I71
J 0
(-500 3200);
DISPLAY 0.872340 (-500 3200);
PAINT AQUA (-500 3200);
DISPLAY INVISIBLE (-500 3200);
FORCEPROP 1 LAST VOLTAGE 0.0V
J 0
(-620 3157);
DISPLAY 0.340426 (-620 3157);
PAINT SKYBLUE (-620 3157);
DISPLAY INVISIBLE (-620 3157);
FORCEPROP 2 LAST CDS_LIB mstr_symbols
J 0
(-575 3200);
PAINT ORANGE (-575 3200);
DISPLAY INVISIBLE (-575 3200);
FORCEADD SWITCH_D37771002..1
R 3
(-7075 2675);
FORCEPROP 1 LASTPIN (-7225 2575) $PN 4
R 1
J 0
(-6975 2510);
DISPLAY 0.617021 (-6975 2510);
PAINT WHITE (-6975 2510);
FORCEPROP 1 LASTPIN (-7225 2775) $PN 3
R 1
J 2
(-6975 2820);
DISPLAY 0.617021 (-6975 2820);
PAINT WHITE (-6975 2820);
FORCEPROP 1 LAST MATERIAL IC
R 1
J 2
(-7105 2470);
DISPLAY 0.617021 (-7105 2470);
PAINT SKYBLUE (-7105 2470);
FORCEPROP 1 LAST LOCATION S9A1
R 1
J 2
(-7155 2470);
DISPLAY 0.617021 (-7155 2470);
PAINT AQUA (-7155 2470);
FORCEPROP 1 LASTPIN (-6975 2775) $PN 1
R 1
J 2
(-7200 2820);
DISPLAY 0.617021 (-7200 2820);
PAINT WHITE (-7200 2820);
FORCEPROP 1 LASTPIN (-6975 2575) $PN 2
R 1
J 0
(-7200 2515);
DISPLAY 0.617021 (-7200 2515);
PAINT WHITE (-7200 2515);
FORCEPROP 1 LAST PART_NUMBER D37771-002
R 1
J 2
(-7050 2470);
DISPLAY 0.617021 (-7050 2470);
PAINT BLUE (-7050 2470);
FORCEPROP 0 LAST BOM_COST MIO_CHASSIS
R 1
J 0
(-7000 2900);
DISPLAY 1.021277 (-7000 2900);
PAINT ORANGE (-7000 2900);
DISPLAY INVISIBLE (-7000 2900);
FORCEPROP 0 LAST ROOM MIO_CHASSIS
R 1
J 0
(-6975 2850);
DISPLAY 1.021277 (-6975 2850);
PAINT ORANGE (-6975 2850);
DISPLAY INVISIBLE (-6975 2850);
FORCEPROP 1 LAST CDS_LMAN_SYM_OUTLINE -100,125,100,-75
R 1
J 2
(-7075 2675);
DISPLAY 0.468085 (-7075 2675);
PAINT GREEN (-7075 2675);
DISPLAY INVISIBLE (-7075 2675);
FORCEPROP 2 LAST CDS_LIB mstr_misc
R 1
J 2
(-7075 2675);
PAINT MONO (-7075 2675);
DISPLAY INVISIBLE (-7075 2675);
FORCEPROP 2 LAST CDS_LOCATION S9A1
R 1
J 2
(-7155 2470);
DISPLAY 0.617021 (-7155 2470);
PAINT AQUA (-7155 2470);
DISPLAY INVISIBLE (-7155 2470);
FORCEPROP 1 LAST PACK_TYPE SM
R 1
J 2
(-7205 2470);
PAINT SKYBLUE (-7205 2470);
DISPLAY INVISIBLE (-7205 2470);
FORCEPROP 2 LAST SEC_TYPE SM
R 1
J 2
(-7225 2450);
DISPLAY 1.021277 (-7225 2450);
PAINT ORANGE (-7225 2450);
DISPLAY INVISIBLE (-7225 2450);
FORCEPROP 2 LAST SEC 1
R 1
J 2
(-7225 2450);
DISPLAY 0.680851 (-7225 2450);
PAINT MONO (-7225 2450);
DISPLAY INVISIBLE (-7225 2450);
FORCEPROP 1 LAST PATH I78
R 1
J 2
(-7100 1975);
PAINT WHITE (-7100 1975);
DISPLAY INVISIBLE (-7100 1975);
FORCEADD SW_H67881001..1
(-7150 4075);
FORCEPROP 2 LASTPIN (-7400 3975) $PN 3
J 2
(-7410 3985);
DISPLAY 0.617021 (-7410 3985);
PAINT MONO (-7410 3985);
FORCEPROP 2 LASTPIN (-6900 4175) $PN 2
J 0
(-6890 4185);
DISPLAY 0.617021 (-6890 4185);
PAINT MONO (-6890 4185);
FORCEPROP 1 LAST MATERIAL IC
J 0
(-7350 4350);
DISPLAY 0.617021 (-7350 4350);
PAINT SKYBLUE (-7350 4350);
FORCEPROP 2 LASTPIN (-7400 4175) $PN 1
J 2
(-7410 4185);
DISPLAY 0.617021 (-7410 4185);
PAINT MONO (-7410 4185);
FORCEPROP 2 LASTPIN (-6900 3975) $PN 4
J 0
(-6890 3985);
DISPLAY 0.617021 (-6890 3985);
PAINT MONO (-6890 3985);
FORCEPROP 1 LAST PART_NUMBER H67881-001
J 0
(-7350 3825);
DISPLAY 0.617021 (-7350 3825);
PAINT BLUE (-7350 3825);
FORCEPROP 1 LAST LOCATION S9A2
J 0
(-7350 4400);
DISPLAY 0.617021 (-7350 4400);
PAINT AQUA (-7350 4400);
FORCEPROP 1 LAST PATH I84
J 0
(-7050 4351);
PAINT GREEN (-7050 4351);
DISPLAY INVISIBLE (-7050 4351);
FORCEPROP 0 LAST BOM_COST MIO_CHASSIS
J 0
(-7350 4600);
DISPLAY 1.021277 (-7350 4600);
PAINT ORANGE (-7350 4600);
DISPLAY INVISIBLE (-7350 4600);
FORCEPROP 1 LAST PACK_TYPE SM
J 0
(-7350 4450);
PAINT SKYBLUE (-7350 4450);
DISPLAY INVISIBLE (-7350 4450);
FORCEPROP 2 LAST CDS_SEC 1
J 0
(-7350 4450);
PAINT MONO (-7350 4450);
DISPLAY INVISIBLE (-7350 4450);
FORCEPROP 2 LAST $SEC 1
J 0
(-7350 4450);
PAINT MONO (-7350 4450);
DISPLAY INVISIBLE (-7350 4450);
FORCEPROP 2 LAST CDS_LOCATION S9A2
J 0
(-7350 4400);
DISPLAY 0.617021 (-7350 4400);
PAINT AQUA (-7350 4400);
DISPLAY INVISIBLE (-7350 4400);
FORCEPROP 0 LAST ROOM MIO_CHASSIS
J 0
(-7350 4500);
DISPLAY 1.021277 (-7350 4500);
PAINT ORANGE (-7350 4500);
DISPLAY INVISIBLE (-7350 4500);
FORCEPROP 2 LAST CDS_LIB mstr_misc
J 0
(-7150 4075);
PAINT MONO (-7150 4075);
DISPLAY INVISIBLE (-7150 4075);
FORCEPROP 1 LAST CDS_LMAN_SYM_OUTLINE -200,200,200,-200
J 0
(-7150 4075);
DISPLAY 0.468085 (-7150 4075);
PAINT GREEN (-7150 4075);
DISPLAY INVISIBLE (-7150 4075);
FORCEADD P3V3_STBY..1
(-3700 1825);
FORCEPROP 3 LASTPIN (-3700 1775) SIG_NAME P3V3_STBY\g
J 0
(-3690 1785);
DISPLAY 0.659574 (-3690 1785);
PAINT MONO (-3690 1785);
DISPLAY INVISIBLE (-3690 1785);
FORCEPROP 1 LAST HDL_POWER P3V3_STBY
J 0
(-4000 1700);
DISPLAY 0.872340 (-4000 1700);
PAINT ORANGE (-4000 1700);
DISPLAY INVISIBLE (-4000 1700);
FORCEPROP 1 LAST BODY_TYPE PLUMBING
J 0
(-3745 1782);
DISPLAY 0.340426 (-3745 1782);
PAINT GREEN (-3745 1782);
DISPLAY INVISIBLE (-3745 1782);
FORCEPROP 1 LAST SIZE 1B
J 0
(-3655 1847);
DISPLAY 0.340426 (-3655 1847);
PAINT GREEN (-3655 1847);
DISPLAY INVISIBLE (-3655 1847);
FORCEPROP 1 LAST PATH I85
J 0
(-3655 1827);
DISPLAY 0.340426 (-3655 1827);
PAINT GREEN (-3655 1827);
DISPLAY INVISIBLE (-3655 1827);
FORCEPROP 2 LAST CDS_LIB mstr_symbols
J 0
(-3700 1825);
PAINT MONO (-3700 1825);
DISPLAY INVISIBLE (-3700 1825);
FORCEPROP 1 LAST VOLTAGE 3.3V
J 0
(-3745 1782);
DISPLAY 0.340426 (-3745 1782);
PAINT SKYBLUE (-3745 1782);
DISPLAY INVISIBLE (-3745 1782);
FORCEADD P5V_STBY..1
(-2900 1975);
FORCEPROP 3 LASTPIN (-2900 1925) SIG_NAME P5V_STBY\g
J 0
(-2890 1935);
DISPLAY 0.659574 (-2890 1935);
PAINT MONO (-2890 1935);
DISPLAY INVISIBLE (-2890 1935);
FORCEPROP 1 LAST HDL_POWER P5V_STBY
J 0
(-3200 1850);
DISPLAY 0.872340 (-3200 1850);
PAINT ORANGE (-3200 1850);
DISPLAY INVISIBLE (-3200 1850);
FORCEPROP 1 LAST BODY_TYPE PLUMBING
J 0
(-2945 1932);
DISPLAY 0.340426 (-2945 1932);
PAINT GREEN (-2945 1932);
DISPLAY INVISIBLE (-2945 1932);
FORCEPROP 1 LAST PATH I86
J 0
(-2855 1977);
DISPLAY 0.340426 (-2855 1977);
PAINT GREEN (-2855 1977);
DISPLAY INVISIBLE (-2855 1977);
FORCEPROP 1 LAST SIZE 1B
J 0
(-2855 1997);
DISPLAY 0.340426 (-2855 1997);
PAINT GREEN (-2855 1997);
DISPLAY INVISIBLE (-2855 1997);
FORCEPROP 2 LAST CDS_LIB mstr_symbols
J 0
(-2900 1975);
PAINT MONO (-2900 1975);
DISPLAY INVISIBLE (-2900 1975);
FORCEPROP 1 LAST VOLTAGE 5.0V
J 0
(-2945 1932);
DISPLAY 0.340426 (-2945 1932);
PAINT SKYBLUE (-2945 1932);
DISPLAY INVISIBLE (-2945 1932);
FORCEADD OFFPAGE..1
(-7325 3525);
FORCEPROP 2 LAST $XR0 247 
J 0
(-7577 3525);
DISPLAY 0.638298 (-7577 3525);
PAINT MONO (-7577 3525);
FORCEPROP 2 LAST $XR1 ?
J 0
(-7697 3525);
DISPLAY 0.638298 (-7697 3525);
PAINT MONO (-7697 3525);
FORCEPROP 2 LAST $XR2 ?
J 0
(-7817 3525);
DISPLAY 0.638298 (-7817 3525);
PAINT MONO (-7817 3525);
FORCEPROP 1 LAST COMMENT_BODY TRUE
J 0
(-7200 3425);
DISPLAY 0.872340 (-7200 3425);
PAINT GREEN (-7200 3425);
DISPLAY INVISIBLE (-7200 3425);
FORCEPROP 1 LAST OFFPAGE TRUE
J 0
(-7000 3400);
DISPLAY 0.872340 (-7000 3400);
PAINT GREEN (-7000 3400);
DISPLAY INVISIBLE (-7000 3400);
FORCEPROP 2 LAST PATH I87
J 0
(-7575 3575);
DISPLAY 1.021277 (-7575 3575);
PAINT ORANGE (-7575 3575);
DISPLAY INVISIBLE (-7575 3575);
FORCEPROP 2 LAST CDS_LIB mstr_standard
J 0
(-7325 3525);
PAINT ORANGE (-7325 3525);
DISPLAY INVISIBLE (-7325 3525);
FORCEADD OFFPAGE..1
(-6250 1550);
FORCEPROP 2 LAST $XR0 146 
J 0
(-6622 1550);
DISPLAY 0.638298 (-6622 1550);
PAINT MONO (-6622 1550);
FORCEPROP 1 LAST COMMENT_BODY TRUE
J 0
(-6125 1450);
DISPLAY 0.872340 (-6125 1450);
PAINT GREEN (-6125 1450);
DISPLAY INVISIBLE (-6125 1450);
FORCEPROP 1 LAST OFFPAGE TRUE
J 0
(-5925 1425);
DISPLAY 0.872340 (-5925 1425);
PAINT GREEN (-5925 1425);
DISPLAY INVISIBLE (-5925 1425);
FORCEPROP 2 LAST CDS_LIB mstr_standard
J 0
(-6250 1550);
PAINT MONO (-6250 1550);
DISPLAY INVISIBLE (-6250 1550);
FORCEPROP 2 LAST PATH I88
J 0
(-6200 1625);
DISPLAY 1.021277 (-6200 1625);
PAINT ORANGE (-6200 1625);
DISPLAY INVISIBLE (-6200 1625);
FORCEADD 0R2J-L-GP..1
R 1
(-5550 1550);
FORCEPROP 1 LAST VALUE 0R2J-L-GP
J 0
(-5425 1575);
DISPLAY 0.617021 (-5425 1575);
PAINT GREEN (-5425 1575);
FORCEPROP 1 LAST LOCATION R1L45
J 0
(-5650 1575);
DISPLAY 0.617021 (-5650 1575);
PAINT GREEN (-5650 1575);
FORCEPROP 1 LAST CDS_LMAN_SYM_OUTLINE -50,75,50,-75
R 1
J 0
(-5550 1550);
DISPLAY 0.468085 (-5550 1550);
PAINT GREEN (-5550 1550);
DISPLAY INVISIBLE (-5550 1550);
FORCEPROP 1 LAST PATH I89
R 1
J 0
(-5550 1550);
DISPLAY 0.617021 (-5550 1550);
PAINT GREEN (-5550 1550);
DISPLAY INVISIBLE (-5550 1550);
FORCEPROP 2 LAST CDS_LIB w_hdl
R 1
J 0
(-5550 1550);
PAINT MONO (-5550 1550);
DISPLAY INVISIBLE (-5550 1550);
FORCEPROP 1 LAST PART_NUMBER 63.R0034.L0L
R 1
J 0
(-5550 1550);
DISPLAY 0.617021 (-5550 1550);
PAINT GREEN (-5550 1550);
DISPLAY INVISIBLE (-5550 1550);
FORCEPROP 1 LAST PACK_TYPE SMD-RG5
R 1
J 0
(-5550 1550);
DISPLAY 0.617021 (-5550 1550);
PAINT GREEN (-5550 1550);
DISPLAY INVISIBLE (-5550 1550);
FORCEADD TTL2G14..1
(-4675 4175);
FORCEPROP 1 LAST POWER_GROUP VCC=P3V3_STBY;GND=GND
J 1
(-4325 3985);
DISPLAY 0.617021 (-4325 3985);
PAINT ORANGE (-4325 3985);
FORCEPROP 2 LASTPIN (-4525 4175) $PN 6
J 0
(-4515 4185);
DISPLAY 0.617021 (-4515 4185);
PAINT ORANGE (-4515 4185);
FORCEPROP 1 LAST VALUE 74LVC2G14
J 0
(-4725 4275);
DISPLAY 0.617021 (-4725 4275);
PAINT SKYBLUE (-4725 4275);
FORCEPROP 1 LAST LOCATION U9A4
J 0
(-4725 4375);
DISPLAY 0.617021 (-4725 4375);
PAINT AQUA (-4725 4375);
FORCEPROP 1 LAST MATERIAL IC
J 0
(-4725 4325);
DISPLAY 0.617021 (-4725 4325);
PAINT SKYBLUE (-4725 4325);
FORCEPROP 2 LASTPIN (-4775 4175) $PN 1
J 2
(-4785 4185);
DISPLAY 0.617021 (-4785 4185);
PAINT ORANGE (-4785 4185);
FORCEPROP 1 LAST PART_NUMBER D18476-001
J 0
(-4725 4040);
DISPLAY 0.617021 (-4725 4040);
PAINT BLUE (-4725 4040);
FORCEPROP 2 LAST ROOM MIO_CHASSIS
J 0
(-4725 4425);
DISPLAY 1.021277 (-4725 4425);
PAINT ORANGE (-4725 4425);
DISPLAY INVISIBLE (-4725 4425);
FORCEPROP 2 LAST CDS_LOCATION U9A4
J 0
(-4725 4375);
DISPLAY 0.617021 (-4725 4375);
PAINT AQUA (-4725 4375);
DISPLAY INVISIBLE (-4725 4375);
FORCEPROP 1 LAST PACK_TYPE SMLF
J 0
(-4725 4425);
DISPLAY 0.978723 (-4725 4425);
PAINT SKYBLUE (-4725 4425);
DISPLAY INVISIBLE (-4725 4425);
FORCEPROP 2 LAST SEC 1
J 0
(-4725 4425);
DISPLAY 0.680851 (-4725 4425);
PAINT MONO (-4725 4425);
DISPLAY INVISIBLE (-4725 4425);
FORCEPROP 2 LAST BOM_COST MIO_CHASSIS
J 0
(-4725 4475);
DISPLAY 1.021277 (-4725 4475);
PAINT ORANGE (-4725 4475);
DISPLAY INVISIBLE (-4725 4475);
FORCEPROP 2 LAST SEC_TYPE SMLF
J 0
(-4725 4425);
DISPLAY 1.021277 (-4725 4425);
PAINT ORANGE (-4725 4425);
DISPLAY INVISIBLE (-4725 4425);
FORCEPROP 2 LAST CDS_LIB mstr_ttl
J 0
(-4675 4175);
PAINT ORANGE (-4675 4175);
DISPLAY INVISIBLE (-4675 4175);
FORCEPROP 1 LAST PATH I9
J 0
(-4625 4225);
DISPLAY 0.978723 (-4625 4225);
PAINT WHITE (-4625 4225);
DISPLAY INVISIBLE (-4625 4225);
FORCEADD CAD_NOTE..1
(-3525 2250);
FORCEPROP 0 LAST L1 PLACE 0.1UF CAP CLOSE TO VCC OF 74AHCT1G86
J 0
(-3675 2125);
DISPLAY 1.021277 (-3675 2125);
PAINT ORANGE (-3675 2125);
FORCEPROP 1 LAST COMMENT_BODY TRUE
J 0
(-3500 2350);
DISPLAY 0.978723 (-3500 2350);
PAINT ORANGE (-3500 2350);
DISPLAY INVISIBLE (-3500 2350);
FORCEPROP 2 LAST CDS_LIB mstr_symbols
J 0
(-3525 2250);
PAINT MONO (-3525 2250);
DISPLAY INVISIBLE (-3525 2250);
FORCEADD CAD_NOTE..1
(-975 3650);
FORCEPROP 0 LAST L2 ON TTL1G07_A
J 2
(-725 3450);
DISPLAY 1.021277 (-725 3450);
PAINT ORANGE (-725 3450);
FORCEPROP 0 LAST L1 PLACE 0.1UF CAP NEXT TO VCC PIN
J 2
(-725 3525);
DISPLAY 1.021277 (-725 3525);
PAINT ORANGE (-725 3525);
FORCEPROP 1 LAST COMMENT_BODY TRUE
J 0
(-950 3750);
DISPLAY 0.978723 (-950 3750);
PAINT ORANGE (-950 3750);
DISPLAY INVISIBLE (-950 3750);
FORCEPROP 2 LAST CDS_LIB mstr_symbols
J 0
(-975 3650);
PAINT ORANGE (-975 3650);
DISPLAY INVISIBLE (-975 3650);
FORCEADD CAD_NOTE..1
(-5700 2100);
FORCEPROP 0 LAST L4 ON BOARD EDGE
J 0
(-5850 1800);
DISPLAY 1.021277 (-5850 1800);
PAINT ORANGE (-5850 1800);
FORCEPROP 0 LAST L3 YELLOW LED SHOULD BE LEFT-MOST LED
J 0
(-5850 1850);
DISPLAY 1.021277 (-5850 1850);
PAINT ORANGE (-5850 1850);
FORCEPROP 0 LAST L2 DEBUG HEADER AND BOARD EDGE
J 0
(-5850 1900);
DISPLAY 1.021277 (-5850 1900);
PAINT ORANGE (-5850 1900);
FORCEPROP 0 LAST L1 PLACE YELLOW LED IN BETWEEN BMC
J 0
(-5850 1950);
DISPLAY 1.021277 (-5850 1950);
PAINT ORANGE (-5850 1950);
FORCEPROP 1 LAST COMMENT_BODY TRUE
J 0
(-5675 2200);
DISPLAY 0.978723 (-5675 2200);
PAINT ORANGE (-5675 2200);
DISPLAY INVISIBLE (-5675 2200);
FORCEPROP 2 LAST CDS_LIB mstr_symbols
J 0
(-5700 2100);
PAINT MONO (-5700 2100);
DISPLAY INVISIBLE (-5700 2100);
FORCEADD INTEL_CORP_BPAGE..1
(-50 125);
FORCEPROP 1 LAST CDS_CON_LAST_MODIFIED Tue Dec 01 11:52:13 2015
J 0
(-1475 450);
DISPLAY 1.382979 (-1475 450);
PAINT GREEN (-1475 450);
DISPLAY INVISIBLE (-1475 450);
FORCEPROP 1 LAST CUSTOM_TXT_CDS <CURRENT_DESIGN_SHEET> OF <TOTAL_DESIGN_SHEETS>
J 0
(-550 150);
PAINT GREEN (-550 150);
FORCEPROP 2 LAST CUSTOM_TXT_CDS <XR_PAGE_TITLE>
J 0
(-7940 5375);
DISPLAY 0.638298 (-7940 5375);
PAINT PINK (-7940 5375);
DISPLAY INVISIBLE (-7940 5375);
FORCEPROP 2 LAST CUSTOM_TXT_CDS <CON_LAST_MODIFIED>
J 0
(-1975 475);
DISPLAY 1.382979 (-1975 475);
PAINT GREEN (-1975 475);
FORCEPROP 1 LAST SCH_ADDRESS3 Santa Clara, CA 95052-8119
J 0
(-4025 150);
DISPLAY 0.617021 (-4025 150);
PAINT YELLOW (-4025 150);
FORCEPROP 1 LAST SCH_REV 2.420
J 0
(-300 275);
DISPLAY 0.978723 (-300 275);
PAINT YELLOW (-300 275);
FORCEPROP 1 LAST SCH_NUMBER H4694802
J 0
(-1350 275);
DISPLAY 1.212766 (-1350 275);
PAINT YELLOW (-1350 275);
FORCEPROP 1 LAST SCH_TITLE PWR, RESET BTN & LEDS
J 0
(-8000 175);
DISPLAY 1.212766 (-8000 175);
PAINT ORANGE (-8000 175);
FORCEPROP 1 LAST SCH_ADDRESS2 P.O. BOX 58119
J 0
(-4025 200);
DISPLAY 0.617021 (-4025 200);
PAINT YELLOW (-4025 200);
FORCEPROP 1 LAST SCH_ADDRESS1 2200 Mission College Blvd.
J 0
(-4025 250);
DISPLAY 0.617021 (-4025 250);
PAINT YELLOW (-4025 250);
FORCEPROP 1 LAST SCH_DEPT BESD
J 1
(-4500 225);
DISPLAY 1.212766 (-4500 225);
PAINT YELLOW (-4500 225);
FORCEPROP 1 LAST COMMENT_BODY TRUE
J 0
(-38 137);
DISPLAY 0.617021 (-38 137);
PAINT PEACH (-38 137);
DISPLAY INVISIBLE (-38 137);
FORCEPROP 2 LAST CDS_LIB mstr_symbols
J 0
(-50 125);
DISPLAY 1.382979 (-50 125);
PAINT ORANGE (-50 125);
DISPLAY INVISIBLE (-50 125);
FORCEPROP 2 LAST PAGE_BORDER TRUE
J 0
(-7940 5375);
DISPLAY 0.872340 (-7940 5375);
PAINT PINK (-7940 5375);
DISPLAY INVISIBLE (-7940 5375);
FORCEPROP 2 LAST CDS_XR_PAGE_TITLE CR-175 : @BASEBOARD_FAB2_LIB.BASEBOARD_FAB2(SCH_1):PAGE175
J 0
(-7940 5375);
DISPLAY 0.638298 (-7940 5375);
PAINT PINK (-7940 5375);
DISPLAY INVISIBLE (-7940 5375);
FORCEADD CAD_NOTE..1
(-3900 4850);
FORCEPROP 0 LAST L1 PLACE 0.1UF CAP NEXT TO VCC PIN ON 74LVC2G14
J 0
(-4050 4700);
DISPLAY 1.021277 (-4050 4700);
PAINT ORANGE (-4050 4700);
FORCEPROP 1 LAST COMMENT_BODY TRUE
J 0
(-3875 4950);
DISPLAY 0.978723 (-3875 4950);
PAINT ORANGE (-3875 4950);
DISPLAY INVISIBLE (-3875 4950);
FORCEPROP 2 LAST CDS_LIB mstr_symbols
J 0
(-3900 4850);
PAINT ORANGE (-3900 4850);
DISPLAY INVISIBLE (-3900 4850);
FORCEADD CAD_NOTE..1
(-4875 3475);
FORCEPROP 0 LAST L2 ON 74LVC2G14
J 2
(-4650 3250);
DISPLAY 1.021277 (-4650 3250);
PAINT ORANGE (-4650 3250);
FORCEPROP 0 LAST L1 PLACE 0.1UF CAP NEXT TO VCC PIN
J 2
(-4650 3325);
DISPLAY 1.021277 (-4650 3325);
PAINT ORANGE (-4650 3325);
FORCEPROP 1 LAST COMMENT_BODY TRUE
J 0
(-4850 3575);
DISPLAY 0.978723 (-4850 3575);
PAINT ORANGE (-4850 3575);
DISPLAY INVISIBLE (-4850 3575);
FORCEPROP 2 LAST CDS_LIB mstr_symbols
J 0
(-4875 3475);
PAINT ORANGE (-4875 3475);
DISPLAY INVISIBLE (-4875 3475);
FORCEADD DNS..2
(-5870 3070);
PAINT RED (-5870 3070);
FORCEPROP 1 LAST COMMENT_BODY TRUE
R 1
J 0
(-5795 2845);
DISPLAY 0.872340 (-5795 2845);
PAINT GREEN (-5795 2845);
DISPLAY INVISIBLE (-5795 2845);
FORCEPROP 2 LAST CDS_LIB mstr_misc
J 0
(-5870 3070);
PAINT ORANGE (-5870 3070);
DISPLAY INVISIBLE (-5870 3070);
WIRE 16 -1 (-4975 3725)(-4975 3850);
WIRE 16 -1 (-4925 2325)(-4925 2450);
WIRE 16 -1 (-5875 3350)(-5875 3175);
WIRE 16 -1 (-7625 2775)(-7225 2775);
WIRE 16 -1 (-7625 2775)(-7625 2575);
WIRE 16 -1 (-7625 2575)(-7225 2575);
WIRE 16 -1 (-7625 2300)(-7625 2575);
WIRE 16 -1 (-6900 3975)(-6750 3975);
WIRE 16 -1 (-6750 3975)(-6750 3775);
WIRE 16 -1 (-6750 3775)(-7675 3775);
WIRE 16 -1 (-7675 3775)(-7675 3975);
WIRE 16 -1 (-7675 3700)(-7675 3775);
WIRE 16 -1 (-7675 3975)(-7400 3975);
WIRE 16 -1 (-4500 3100)(-4500 3250);
WIRE 16 -1 (-4400 4575)(-4400 4475);
WIRE 16 -1 (-4400 4850)(-4400 4775);
WIRE 16 -1 (-4500 3600)(-4500 3450);
WIRE 16 -1 (-5025 800)(-5025 975);
WIRE 16 -1 (-1175 1650)(-1175 1450);
WIRE 16 -1 (-5925 4750)(-5925 4575);
WIRE 16 -1 (-2900 1625)(-2900 1525);
WIRE 16 -1 (-575 3750)(-575 3600);
WIRE 16 -1 (-575 3250)(-575 3400);
WIRE 16 -1 (-3900 1550)(-3700 1550);
WIRE 16 -1 (-3700 1775)(-3700 1550);
WIRE 16 -1 (-2900 1925)(-2900 1825);
WIRE 16 -1 (-4100 1550)(-4500 1550);
FORCEPROP 2 LAST SIG_NAME FM_BEEP_LED_P
J 0
(-4410 1560);
DISPLAY 0.617021 (-4410 1560);
PAINT ORANGE (-4410 1560);
FORCEPROP 2 LASTPROP $XRERR UNIQUE?
J 0
(-4650 1560);
DISPLAY 0.638298 (-4650 1560);
PAINT MONO (-4650 1560);
DISPLAY INVISIBLE (-4650 1560);
WIRE 16 -1 (-3525 2775)(-2325 2775);
FORCEPROP 2 LAST SIG_NAME RST_SYSTEM_BTN_BUF_N
J 0
(-3235 2800);
DISPLAY 0.617021 (-3235 2800);
PAINT ORANGE (-3235 2800);
FORCEPROP 2 LASTPROP $XRERR UNIQUE?
J 0
(-3475 2800);
DISPLAY 0.638298 (-3475 2800);
PAINT MONO (-3475 2800);
DISPLAY INVISIBLE (-3475 2800);
WIRE 16 -1 (-2125 2775)(-1500 2775);
FORCEPROP 2 LAST SIG_NAME RST_SYSTEM_BTN_N
J 0
(-2060 2785);
DISPLAY 0.617021 (-2060 2785);
PAINT ORANGE (-2060 2785);
WIRE 16 -1 (-1175 1250)(-1175 1025);
WIRE 16 -1 (-1175 1025)(-1600 1025);
FORCEPROP 2 LAST SIG_NAME FP_ID_LED_XOR_R
J 0
(-1535 1035);
DISPLAY 0.617021 (-1535 1035);
PAINT ORANGE (-1535 1035);
FORCEPROP 2 LASTPROP $XRERR UNIQUE?
J 0
(-1775 1035);
DISPLAY 0.638298 (-1775 1035);
PAINT MONO (-1775 1035);
DISPLAY INVISIBLE (-1775 1035);
WIRE 16 -1 (-6750 4175)(-5925 4175);
FORCEPROP 2 LAST SIG_NAME FP_PWR_BTN_R_N
J 0
(-6685 4185);
DISPLAY 0.617021 (-6685 4185);
PAINT ORANGE (-6685 4185);
WIRE 16 -1 (-6900 4175)(-6750 4175);
WIRE 16 -1 (-6750 4500)(-6750 4175);
WIRE 16 -1 (-5925 4175)(-5750 4175);
WIRE 16 -1 (-5925 4375)(-5925 4175);
WIRE 16 -1 (-5925 3525)(-5925 4175);
WIRE 16 -1 (-7275 3525)(-5925 3525);
WIRE 16 -1 (-7675 4500)(-6750 4500);
WIRE 16 -1 (-7675 4175)(-7675 4500);
WIRE 16 -1 (-7400 4175)(-7675 4175);
WIRE 3 2175 (-8000 3600)(-6625 3600);
WIRE 3 2175 (-8000 3600)(-8000 3400);
WIRE 3 2175 (-6625 3600)(-6625 3400);
WIRE 3 2175 (-8000 3400)(-6625 3400);
WIRE 16 -1 (-7500 1925)(-6100 1925);
FORCEPROP 2 LAST SIG_NAME FM_DEBUG_RST_BTN_N
J 0
(-7385 1935);
DISPLAY 0.617021 (-7385 1935);
PAINT ORANGE (-7385 1935);
WIRE 16 -1 (-6100 1925)(-6100 2475);
WIRE 16 -1 (-6100 2475)(-6100 2775);
WIRE 16 -1 (-6975 2475)(-6100 2475);
WIRE 16 -1 (-6975 2475)(-6975 2575);
WIRE 16 -1 (-6100 2775)(-5875 2775);
WIRE 16 -1 (-6975 2775)(-6100 2775);
WIRE 16 -1 (-5875 2975)(-5875 2775);
WIRE 16 -1 (-5875 2775)(-5700 2775);
WIRE 16 -1 (-4025 975)(-2950 975);
FORCEPROP 2 LAST SIG_NAME FP_PWR_ID_LED_N
J 0
(-3960 985);
DISPLAY 0.617021 (-3960 985);
PAINT ORANGE (-3960 985);
WIRE 16 -1 (-5850 1075)(-5225 1075);
FORCEPROP 2 LAST SIG_NAME FM_BIOS_TOP_SWAP_SPKR
J 0
(-5835 1085);
DISPLAY 0.617021 (-5835 1085);
PAINT ORANGE (-5835 1085);
WIRE 16 -1 (-5675 1550)(-6200 1550);
FORCEPROP 2 LAST SIG_NAME FM_SPEAKER_PCH_N
J 0
(-6160 1560);
DISPLAY 0.617021 (-6160 1560);
PAINT ORANGE (-6160 1560);
WIRE 16 -1 (-4025 1075)(-3625 1075);
FORCEPROP 2 LAST SIG_NAME PWRGD_P3V3
J 0
(-3960 1085);
DISPLAY 0.617021 (-3960 1085);
PAINT ORANGE (-3960 1085);
WIRE 16 -1 (-4475 2775)(-3775 2775);
FORCEPROP 2 LAST SIG_NAME FP_RST_BTN_BUF1_N
J 0
(-4360 2785);
DISPLAY 0.617021 (-4360 2785);
PAINT ORANGE (-4360 2785);
FORCEPROP 2 LASTPROP $XRERR UNIQUE?
J 0
(-4600 2785);
DISPLAY 0.638298 (-4600 2785);
PAINT MONO (-4600 2785);
DISPLAY INVISIBLE (-4600 2785);
WIRE 16 -1 (-5500 2775)(-4925 2775);
FORCEPROP 2 LAST SIG_NAME FP_RST_BTN_R_N
J 0
(-5435 2785);
DISPLAY 0.617021 (-5435 2785);
PAINT ORANGE (-5435 2785);
FORCEPROP 2 LASTPROP $XRERR UNIQUE?
J 0
(-5675 2785);
DISPLAY 0.638298 (-5675 2785);
PAINT MONO (-5675 2785);
DISPLAY INVISIBLE (-5675 2785);
WIRE 16 -1 (-4925 2775)(-4725 2775);
WIRE 16 -1 (-4925 2650)(-4925 2775);
WIRE 16 -1 (-5550 4175)(-4975 4175);
FORCEPROP 2 LAST SIG_NAME FP_PWR_BTN_R1_N
J 0
(-5485 4185);
DISPLAY 0.617021 (-5485 4185);
PAINT ORANGE (-5485 4185);
FORCEPROP 2 LASTPROP $XRERR UNIQUE?
J 0
(-5725 4185);
DISPLAY 0.638298 (-5725 4185);
PAINT MONO (-5725 4185);
DISPLAY INVISIBLE (-5725 4185);
WIRE 16 -1 (-4975 4175)(-4775 4175);
WIRE 16 -1 (-4975 4050)(-4975 4175);
WIRE 16 -1 (-4525 4175)(-3825 4175);
FORCEPROP 2 LAST SIG_NAME FP_PWR_BTN_BUF1_N
J 0
(-4435 4185);
DISPLAY 0.617021 (-4435 4185);
PAINT ORANGE (-4435 4185);
FORCEPROP 2 LASTPROP $XRERR UNIQUE?
J 0
(-4675 4185);
DISPLAY 0.638298 (-4675 4185);
PAINT MONO (-4675 4185);
DISPLAY INVISIBLE (-4675 4185);
WIRE 16 -1 (-3425 1075)(-2950 1075);
FORCEPROP 2 LAST SIG_NAME PWRGD_P3V3_R
J 0
(-3360 1085);
DISPLAY 0.617021 (-3360 1085);
PAINT ORANGE (-3360 1085);
FORCEPROP 2 LASTPROP $XRERR UNIQUE?
J 0
(-3600 1085);
DISPLAY 0.638298 (-3600 1085);
PAINT MONO (-3600 1085);
DISPLAY INVISIBLE (-3600 1085);
WIRE 16 -1 (-2450 1025)(-1800 1025);
FORCEPROP 2 LAST SIG_NAME FP_ID_LED_P5V_STBY_N
J 0
(-2360 1035);
DISPLAY 0.617021 (-2360 1035);
PAINT ORANGE (-2360 1035);
FORCEPROP 2 LASTPROP $XRERR UNIQUE?
J 0
(-2600 1035);
DISPLAY 0.638298 (-2600 1035);
PAINT MONO (-2600 1035);
DISPLAY INVISIBLE (-2600 1035);
WIRE 16 -1 (-2850 4175)(-3575 4175);
FORCEPROP 2 LAST SIG_NAME FM_PWR_BTN_R_N
J 0
(-3485 4185);
DISPLAY 0.617021 (-3485 4185);
PAINT ORANGE (-3485 4185);
FORCEPROP 2 LASTPROP $XRERR UNIQUE?
J 0
(-3725 4185);
DISPLAY 0.638298 (-3725 4185);
PAINT MONO (-3725 4185);
DISPLAY INVISIBLE (-3725 4185);
WIRE 16 -1 (-2650 4175)(-1875 4175);
FORCEPROP 2 LAST SIG_NAME FM_PWR_BTN_N
J 0
(-2485 4185);
DISPLAY 0.617021 (-2485 4185);
PAINT ORANGE (-2485 4185);
WIRE 16 -1 (-5425 1550)(-5025 1550);
FORCEPROP 2 LAST SIG_NAME FM_SPEAKER_PCH_N_R
J 0
(-5235 1560);
DISPLAY 0.617021 (-5235 1560);
PAINT ORANGE (-5235 1560);
FORCEPROP 2 LASTPROP $XRERR UNIQUE?
J 0
(-5475 1560);
DISPLAY 0.638298 (-5475 1560);
PAINT MONO (-5475 1560);
DISPLAY INVISIBLE (-5475 1560);
WIRE 16 -1 (-5025 1550)(-4700 1550);
WIRE 16 -1 (-5025 1375)(-5025 1550);
WIRE 3 273 (-6500 1300)(-4800 1300);
WIRE 3 273 (-6500 1700)(-6500 1300);
WIRE 3 273 (-4800 1700)(-4800 1300);
WIRE 3 273 (-4800 1700)(-6500 1700);
DOT 1 (-7675 3775);
DOT 1 (-6100 2775);
DOT 1 (-5875 2775);
DOT 1 (-4925 2775);
DOT 1 (-6750 4175);
DOT 1 (-4975 4175);
DOT 1 (-5925 4175);
DOT 1 (-6100 2475);
DOT 1 (-5025 1550);
DOT 1 (-7625 2575);
FORCENOTE
IF = 25MA
(-1800 800) 0;
DISPLAY LEFT (-1800 800);
DISPLAY 1.021277 (-1800 800);
PAINT PURPLE (-1800 800);
FORCENOTE
IF = 25MA
(-4700 1325) 0;
DISPLAY LEFT (-4700 1325);
DISPLAY 1.021277 (-4700 1325);
PAINT PURPLE (-4700 1325);
FORCENOTE
IR = 14.9MA
(-3675 1575) 0;
DISPLAY LEFT (-3675 1575);
DISPLAY 1.021277 (-3675 1575);
PAINT PURPLE (-3675 1575);
FORCENOTE
TP FAB1 ADD OFFPAGE 1117
(-7525 3325) 0;
DISPLAY LEFT (-7525 3325);
DISPLAY 1.021277 (-7525 3325);
PAINT RED (-7525 3325);
FORCENOTE
TP FAB1 ADD FROM BMC GPIO 1119
(-6125 1725) 0;
DISPLAY LEFT (-6125 1725);
DISPLAY 1.021277 (-6125 1725);
PAINT RED (-6125 1725);
FORCENOTE
IR = 10.6MA
(-1125 1025) 0;
DISPLAY LEFT (-1125 1025);
DISPLAY 1.021277 (-1125 1025);
PAINT PURPLE (-1125 1025);
QUIT
